G04 ================== begin FILE IDENTIFICATION RECORD ==================*
G04 Layout Name:  D:/<user>/Wistron_project/16317-1/gbr/16317-1.brd*
G04 Film Name:    BSMD*
G04 File Format:  Gerber RS274X*
G04 File Origin:  Cadence Allegro 16.5-S056*
G04 Origin Date:  Fri Jun 09 15:52:42 2017*
G04 *
G04 Layer:  VIA CLASS/PASTEMASK_BOTTOM*
G04 Layer:  PIN/PASTEMASK_BOTTOM*
G04 Layer:  PACKAGE GEOMETRY/PASTEMASK_BOTTOM*
G04 Layer:  DRAWING FORMAT/LAYER_PCB_STORY*
G04 Layer:  DRAWING FORMAT/LAYER_PAST_B*
G04 Layer:  BOARD GEOMETRY/PANEL_OUTLINE*
G04 *
G04 Offset:    (0.00 0.00)*
G04 Mirror:    No*
G04 Mode:      Positive*
G04 Rotation:  0*
G04 FullContactRelief:  No*
G04 UndefLineWidth:     6.00*
G04 ================== end FILE IDENTIFICATION RECORD ====================*
%FSLAX35Y35*MOIN*%
%IR0*IPPOS*OFA0.00000B0.00000*MIA0B0*SFA1.00000B1.00000*%
%AMMACRO39*
4,1,40,.011,.007,
.011,-.007,
.010939,-.007695,
.010759,-.008368,
.010464,-.009,
.010064,-.009571,
.009571,-.010064,
.009,-.010464,
.008368,-.010759,
.007695,-.010939,
.007,-.011,
-.007,-.011,
-.007695,-.010939,
-.008368,-.010759,
-.009,-.010464,
-.009571,-.010064,
-.010064,-.009571,
-.010464,-.009,
-.010759,-.008368,
-.010939,-.007695,
-.011,-.007,
-.011,.007,
-.010939,.007695,
-.010759,.008368,
-.010464,.009,
-.010064,.009571,
-.009571,.010064,
-.009,.010464,
-.008368,.010759,
-.007695,.010939,
-.007,.011,
.007,.011,
.007695,.010939,
.008368,.010759,
.009,.010464,
.009571,.010064,
.010064,.009571,
.010464,.009,
.010759,.008368,
.010939,.007695,
.011,.007,
0.0*
%
%ADD39MACRO39*%
%AMMACRO34*
4,1,40,.013,-.017,
-.013,-.017,
-.013695,-.016939,
-.014368,-.016759,
-.015,-.016464,
-.015571,-.016064,
-.016064,-.015571,
-.016464,-.015,
-.016759,-.014368,
-.016939,-.013695,
-.017,-.013,
-.017,.013,
-.016939,.013695,
-.016759,.014368,
-.016464,.015,
-.016064,.015571,
-.015571,.016064,
-.015,.016464,
-.014368,.016759,
-.013695,.016939,
-.013,.017,
.013,.017,
.013695,.016939,
.014368,.016759,
.015,.016464,
.015571,.016064,
.016064,.015571,
.016464,.015,
.016759,.014368,
.016939,.013695,
.017,.013,
.017,-.013,
.016939,-.013695,
.016759,-.014368,
.016464,-.015,
.016064,-.015571,
.015571,-.016064,
.015,-.016464,
.014368,-.016759,
.013695,-.016939,
.013,-.017,
0.0*
%
%ADD34MACRO34*%
%AMMACRO22*
4,1,40,-.017,-.013,
-.017,.013,
-.016939,.013695,
-.016759,.014368,
-.016464,.015,
-.016064,.015571,
-.015571,.016064,
-.015,.016464,
-.014368,.016759,
-.013695,.016939,
-.013,.017,
.013,.017,
.013695,.016939,
.014368,.016759,
.015,.016464,
.015571,.016064,
.016064,.015571,
.016464,.015,
.016759,.014368,
.016939,.013695,
.017,.013,
.017,-.013,
.016939,-.013695,
.016759,-.014368,
.016464,-.015,
.016064,-.015571,
.015571,-.016064,
.015,-.016464,
.014368,-.016759,
.013695,-.016939,
.013,-.017,
-.013,-.017,
-.013695,-.016939,
-.014368,-.016759,
-.015,-.016464,
-.015571,-.016064,
-.016064,-.015571,
-.016464,-.015,
-.016759,-.014368,
-.016939,-.013695,
-.017,-.013,
0.0*
%
%ADD22MACRO22*%
%AMMACRO25*
4,1,3,0.0,-.0125,
.025,.0125,
-.025,.0125,
0.0,-.0125,
0.0*
%
%ADD25MACRO25*%
%ADD10C,.04*%
%ADD47C,.032*%
%ADD29C,.024*%
%ADD51R,.062X.062*%
%AMMACRO37*
4,1,40,.007,-.0225,
.008389,-.022378,
.009736,-.022018,
.011,-.021428,
.012142,-.020628,
.013128,-.019642,
.013928,-.0185,
.014518,-.017236,
.014878,-.015889,
.015,-.0145,
.015,.0145,
.014878,.015889,
.014518,.017236,
.013928,.0185,
.013128,.019642,
.012142,.020628,
.011,.021428,
.009736,.022018,
.008389,.022378,
.007,.0225,
-.007,.0225,
-.008389,.022378,
-.009736,.022018,
-.011,.021428,
-.012142,.020628,
-.013128,.019642,
-.013928,.0185,
-.014518,.017236,
-.014878,.015889,
-.015,.0145,
-.015,-.0145,
-.014878,-.015889,
-.014518,-.017236,
-.013928,-.0185,
-.013128,-.019642,
-.012142,-.020628,
-.011,-.021428,
-.009736,-.022018,
-.008389,-.022378,
-.007,-.0225,
.007,-.0225,
0.0*
%
%ADD37MACRO37*%
%AMMACRO45*
4,1,40,.007,-.011,
-.007,-.011,
-.007695,-.010939,
-.008368,-.010759,
-.009,-.010464,
-.009571,-.010064,
-.010064,-.009571,
-.010464,-.009,
-.010759,-.008368,
-.010939,-.007695,
-.011,-.007,
-.011,.007,
-.010939,.007695,
-.010759,.008368,
-.010464,.009,
-.010064,.009571,
-.009571,.010064,
-.009,.010464,
-.008368,.010759,
-.007695,.010939,
-.007,.011,
.007,.011,
.007695,.010939,
.008368,.010759,
.009,.010464,
.009571,.010064,
.010064,.009571,
.010464,.009,
.010759,.008368,
.010939,.007695,
.011,.007,
.011,-.007,
.010939,-.007695,
.010759,-.008368,
.010464,-.009,
.010064,-.009571,
.009571,-.010064,
.009,-.010464,
.008368,-.010759,
.007695,-.010939,
.007,-.011,
0.0*
%
%ADD45MACRO45*%
%AMMACRO15*
4,1,40,-.011,-.007,
-.011,.007,
-.010939,.007695,
-.010759,.008368,
-.010464,.009,
-.010064,.009571,
-.009571,.010064,
-.009,.010464,
-.008368,.010759,
-.007695,.010939,
-.007,.011,
.007,.011,
.007695,.010939,
.008368,.010759,
.009,.010464,
.009571,.010064,
.010064,.009571,
.010464,.009,
.010759,.008368,
.010939,.007695,
.011,.007,
.011,-.007,
.010939,-.007695,
.010759,-.008368,
.010464,-.009,
.010064,-.009571,
.009571,-.010064,
.009,-.010464,
.008368,-.010759,
.007695,-.010939,
.007,-.011,
-.007,-.011,
-.007695,-.010939,
-.008368,-.010759,
-.009,-.010464,
-.009571,-.010064,
-.010064,-.009571,
-.010464,-.009,
-.010759,-.008368,
-.010939,-.007695,
-.011,-.007,
0.0*
%
%ADD15MACRO15*%
%AMMACRO14*
4,1,40,-.012,-.008,
-.012,.008,
-.011939,.008695,
-.011759,.009368,
-.011464,.01,
-.011064,.010571,
-.010571,.011064,
-.01,.011464,
-.009368,.011759,
-.008695,.011939,
-.008,.012,
.008,.012,
.008695,.011939,
.009368,.011759,
.01,.011464,
.010571,.011064,
.011064,.010571,
.011464,.01,
.011759,.009368,
.011939,.008695,
.012,.008,
.012,-.008,
.011939,-.008695,
.011759,-.009368,
.011464,-.01,
.011064,-.010571,
.010571,-.011064,
.01,-.011464,
.009368,-.011759,
.008695,-.011939,
.008,-.012,
-.008,-.012,
-.008695,-.011939,
-.009368,-.011759,
-.01,-.011464,
-.010571,-.011064,
-.011064,-.010571,
-.011464,-.01,
-.011759,-.009368,
-.011939,-.008695,
-.012,-.008,
0.0*
%
%ADD14MACRO14*%
%AMMACRO41*
4,1,40,-.008,.012,
.008,.012,
.008695,.011939,
.009368,.011759,
.01,.011464,
.010571,.011064,
.011064,.010571,
.011464,.01,
.011759,.009368,
.011939,.008695,
.012,.008,
.012,-.008,
.011939,-.008695,
.011759,-.009368,
.011464,-.01,
.011064,-.010571,
.010571,-.011064,
.01,-.011464,
.009368,-.011759,
.008695,-.011939,
.008,-.012,
-.008,-.012,
-.008695,-.011939,
-.009368,-.011759,
-.01,-.011464,
-.010571,-.011064,
-.011064,-.010571,
-.011464,-.01,
-.011759,-.009368,
-.011939,-.008695,
-.012,-.008,
-.012,.008,
-.011939,.008695,
-.011759,.009368,
-.011464,.01,
-.011064,.010571,
-.010571,.011064,
-.01,.011464,
-.009368,.011759,
-.008695,.011939,
-.008,.012,
0.0*
%
%ADD41MACRO41*%
%AMMACRO19*
4,1,40,-.013,.017,
.013,.017,
.013695,.016939,
.014368,.016759,
.015,.016464,
.015571,.016064,
.016064,.015571,
.016464,.015,
.016759,.014368,
.016939,.013695,
.017,.013,
.017,-.013,
.016939,-.013695,
.016759,-.014368,
.016464,-.015,
.016064,-.015571,
.015571,-.016064,
.015,-.016464,
.014368,-.016759,
.013695,-.016939,
.013,-.017,
-.013,-.017,
-.013695,-.016939,
-.014368,-.016759,
-.015,-.016464,
-.015571,-.016064,
-.016064,-.015571,
-.016464,-.015,
-.016759,-.014368,
-.016939,-.013695,
-.017,-.013,
-.017,.013,
-.016939,.013695,
-.016759,.014368,
-.016464,.015,
-.016064,.015571,
-.015571,.016064,
-.015,.016464,
-.014368,.016759,
-.013695,.016939,
-.013,.017,
0.0*
%
%ADD19MACRO19*%
%AMMACRO48*
4,1,40,.017,.013,
.017,-.013,
.016939,-.013695,
.016759,-.014368,
.016464,-.015,
.016064,-.015571,
.015571,-.016064,
.015,-.016464,
.014368,-.016759,
.013695,-.016939,
.013,-.017,
-.013,-.017,
-.013695,-.016939,
-.014368,-.016759,
-.015,-.016464,
-.015571,-.016064,
-.016064,-.015571,
-.016464,-.015,
-.016759,-.014368,
-.016939,-.013695,
-.017,-.013,
-.017,.013,
-.016939,.013695,
-.016759,.014368,
-.016464,.015,
-.016064,.015571,
-.015571,.016064,
-.015,.016464,
-.014368,.016759,
-.013695,.016939,
-.013,.017,
.013,.017,
.013695,.016939,
.014368,.016759,
.015,.016464,
.015571,.016064,
.016064,.015571,
.016464,.015,
.016759,.014368,
.016939,.013695,
.017,.013,
0.0*
%
%ADD48MACRO48*%
%AMMACRO46*
4,1,40,.007,-.011,
-.007,-.011,
-.007695,-.010939,
-.008368,-.010759,
-.009,-.010464,
-.009571,-.010064,
-.010064,-.009571,
-.010464,-.009,
-.010759,-.008368,
-.010939,-.007695,
-.011,-.007,
-.011,.007,
-.010939,.007695,
-.010759,.008368,
-.010464,.009,
-.010064,.009571,
-.009571,.010064,
-.009,.010464,
-.008368,.010759,
-.007695,.010939,
-.007,.011,
.007,.011,
.007695,.010939,
.008368,.010759,
.009,.010464,
.009571,.010064,
.010064,.009571,
.010464,.009,
.010759,.008368,
.010939,.007695,
.011,.007,
.011,-.007,
.010939,-.007695,
.010759,-.008368,
.010464,-.009,
.010064,-.009571,
.009571,-.010064,
.009,-.010464,
.008368,-.010759,
.007695,-.010939,
.007,-.011,
0.0*
%
%ADD46MACRO46*%
%AMMACRO16*
4,1,40,-.011,-.007,
-.011,.007,
-.010939,.007695,
-.010759,.008368,
-.010464,.009,
-.010064,.009571,
-.009571,.010064,
-.009,.010464,
-.008368,.010759,
-.007695,.010939,
-.007,.011,
.007,.011,
.007695,.010939,
.008368,.010759,
.009,.010464,
.009571,.010064,
.010064,.009571,
.010464,.009,
.010759,.008368,
.010939,.007695,
.011,.007,
.011,-.007,
.010939,-.007695,
.010759,-.008368,
.010464,-.009,
.010064,-.009571,
.009571,-.010064,
.009,-.010464,
.008368,-.010759,
.007695,-.010939,
.007,-.011,
-.007,-.011,
-.007695,-.010939,
-.008368,-.010759,
-.009,-.010464,
-.009571,-.010064,
-.010064,-.009571,
-.010464,-.009,
-.010759,-.008368,
-.010939,-.007695,
-.011,-.007,
0.0*
%
%ADD16MACRO16*%
%AMMACRO13*
4,1,40,-.012,-.008,
-.012,.008,
-.011939,.008695,
-.011759,.009368,
-.011464,.01,
-.011064,.010571,
-.010571,.011064,
-.01,.011464,
-.009368,.011759,
-.008695,.011939,
-.008,.012,
.008,.012,
.008695,.011939,
.009368,.011759,
.01,.011464,
.010571,.011064,
.011064,.010571,
.011464,.01,
.011759,.009368,
.011939,.008695,
.012,.008,
.012,-.008,
.011939,-.008695,
.011759,-.009368,
.011464,-.01,
.011064,-.010571,
.010571,-.011064,
.01,-.011464,
.009368,-.011759,
.008695,-.011939,
.008,-.012,
-.008,-.012,
-.008695,-.011939,
-.009368,-.011759,
-.01,-.011464,
-.010571,-.011064,
-.011064,-.010571,
-.011464,-.01,
-.011759,-.009368,
-.011939,-.008695,
-.012,-.008,
0.0*
%
%ADD13MACRO13*%
%AMMACRO40*
4,1,40,-.008,.012,
.008,.012,
.008695,.011939,
.009368,.011759,
.01,.011464,
.010571,.011064,
.011064,.010571,
.011464,.01,
.011759,.009368,
.011939,.008695,
.012,.008,
.012,-.008,
.011939,-.008695,
.011759,-.009368,
.011464,-.01,
.011064,-.010571,
.010571,-.011064,
.01,-.011464,
.009368,-.011759,
.008695,-.011939,
.008,-.012,
-.008,-.012,
-.008695,-.011939,
-.009368,-.011759,
-.01,-.011464,
-.010571,-.011064,
-.011064,-.010571,
-.011464,-.01,
-.011759,-.009368,
-.011939,-.008695,
-.012,-.008,
-.012,.008,
-.011939,.008695,
-.011759,.009368,
-.011464,.01,
-.011064,.010571,
-.010571,.011064,
-.01,.011464,
-.009368,.011759,
-.008695,.011939,
-.008,.012,
0.0*
%
%ADD40MACRO40*%
%AMMACRO20*
4,1,40,-.013,.017,
.013,.017,
.013695,.016939,
.014368,.016759,
.015,.016464,
.015571,.016064,
.016064,.015571,
.016464,.015,
.016759,.014368,
.016939,.013695,
.017,.013,
.017,-.013,
.016939,-.013695,
.016759,-.014368,
.016464,-.015,
.016064,-.015571,
.015571,-.016064,
.015,-.016464,
.014368,-.016759,
.013695,-.016939,
.013,-.017,
-.013,-.017,
-.013695,-.016939,
-.014368,-.016759,
-.015,-.016464,
-.015571,-.016064,
-.016064,-.015571,
-.016464,-.015,
-.016759,-.014368,
-.016939,-.013695,
-.017,-.013,
-.017,.013,
-.016939,.013695,
-.016759,.014368,
-.016464,.015,
-.016064,.015571,
-.015571,.016064,
-.015,.016464,
-.014368,.016759,
-.013695,.016939,
-.013,.017,
0.0*
%
%ADD20MACRO20*%
%AMMACRO49*
4,1,40,.017,.013,
.017,-.013,
.016939,-.013695,
.016759,-.014368,
.016464,-.015,
.016064,-.015571,
.015571,-.016064,
.015,-.016464,
.014368,-.016759,
.013695,-.016939,
.013,-.017,
-.013,-.017,
-.013695,-.016939,
-.014368,-.016759,
-.015,-.016464,
-.015571,-.016064,
-.016064,-.015571,
-.016464,-.015,
-.016759,-.014368,
-.016939,-.013695,
-.017,-.013,
-.017,.013,
-.016939,.013695,
-.016759,.014368,
-.016464,.015,
-.016064,.015571,
-.015571,.016064,
-.015,.016464,
-.014368,.016759,
-.013695,.016939,
-.013,.017,
.013,.017,
.013695,.016939,
.014368,.016759,
.015,.016464,
.015571,.016064,
.016064,.015571,
.016464,.015,
.016759,.014368,
.016939,.013695,
.017,.013,
0.0*
%
%ADD49MACRO49*%
%ADD43R,.06X.03*%
%ADD36R,.022X.04*%
%AMMACRO26*
4,1,3,.025,-.0125,
0.0,.0125,
-.025,-.0125,
.025,-.0125,
0.0*
%
%ADD26MACRO26*%
%ADD35R,.13X.128*%
%ADD28R,.044X.012*%
%ADD54R,.036X.012*%
%ADD52R,.012X.036*%
%ADD44R,.105X.128*%
%ADD55R,.037X.012*%
%ADD53R,.012X.037*%
%ADD50R,.05X.065*%
%ADD24R,.045X.055*%
%ADD23R,.055X.045*%
%ADD42R,.073X.047*%
%ADD30R,.095X.09*%
%AMMACRO32*
4,1,40,.012,.008,
.012,-.008,
.011939,-.008695,
.011759,-.009368,
.011464,-.01,
.011064,-.010571,
.010571,-.011064,
.01,-.011464,
.009368,-.011759,
.008695,-.011939,
.008,-.012,
-.008,-.012,
-.008695,-.011939,
-.009368,-.011759,
-.01,-.011464,
-.010571,-.011064,
-.011064,-.010571,
-.011464,-.01,
-.011759,-.009368,
-.011939,-.008695,
-.012,-.008,
-.012,.008,
-.011939,.008695,
-.011759,.009368,
-.011464,.01,
-.011064,.010571,
-.010571,.011064,
-.01,.011464,
-.009368,.011759,
-.008695,.011939,
-.008,.012,
.008,.012,
.008695,.011939,
.009368,.011759,
.01,.011464,
.010571,.011064,
.011064,.010571,
.011464,.01,
.011759,.009368,
.011939,.008695,
.012,.008,
0.0*
%
%ADD32MACRO32*%
%AMMACRO17*
4,1,40,-.007,.011,
.007,.011,
.007695,.010939,
.008368,.010759,
.009,.010464,
.009571,.010064,
.010064,.009571,
.010464,.009,
.010759,.008368,
.010939,.007695,
.011,.007,
.011,-.007,
.010939,-.007695,
.010759,-.008368,
.010464,-.009,
.010064,-.009571,
.009571,-.010064,
.009,-.010464,
.008368,-.010759,
.007695,-.010939,
.007,-.011,
-.007,-.011,
-.007695,-.010939,
-.008368,-.010759,
-.009,-.010464,
-.009571,-.010064,
-.010064,-.009571,
-.010464,-.009,
-.010759,-.008368,
-.010939,-.007695,
-.011,-.007,
-.011,.007,
-.010939,.007695,
-.010759,.008368,
-.010464,.009,
-.010064,.009571,
-.009571,.010064,
-.009,.010464,
-.008368,.010759,
-.007695,.010939,
-.007,.011,
0.0*
%
%ADD17MACRO17*%
%AMMACRO12*
4,1,40,.008,-.012,
-.008,-.012,
-.008695,-.011939,
-.009368,-.011759,
-.01,-.011464,
-.010571,-.011064,
-.011064,-.010571,
-.011464,-.01,
-.011759,-.009368,
-.011939,-.008695,
-.012,-.008,
-.012,.008,
-.011939,.008695,
-.011759,.009368,
-.011464,.01,
-.011064,.010571,
-.010571,.011064,
-.01,.011464,
-.009368,.011759,
-.008695,.011939,
-.008,.012,
.008,.012,
.008695,.011939,
.009368,.011759,
.01,.011464,
.010571,.011064,
.011064,.010571,
.011464,.01,
.011759,.009368,
.011939,.008695,
.012,.008,
.012,-.008,
.011939,-.008695,
.011759,-.009368,
.011464,-.01,
.011064,-.010571,
.010571,-.011064,
.01,-.011464,
.009368,-.011759,
.008695,-.011939,
.008,-.012,
0.0*
%
%ADD12MACRO12*%
%AMMACRO38*
4,1,40,.011,.007,
.011,-.007,
.010939,-.007695,
.010759,-.008368,
.010464,-.009,
.010064,-.009571,
.009571,-.010064,
.009,-.010464,
.008368,-.010759,
.007695,-.010939,
.007,-.011,
-.007,-.011,
-.007695,-.010939,
-.008368,-.010759,
-.009,-.010464,
-.009571,-.010064,
-.010064,-.009571,
-.010464,-.009,
-.010759,-.008368,
-.010939,-.007695,
-.011,-.007,
-.011,.007,
-.010939,.007695,
-.010759,.008368,
-.010464,.009,
-.010064,.009571,
-.009571,.010064,
-.009,.010464,
-.008368,.010759,
-.007695,.010939,
-.007,.011,
.007,.011,
.007695,.010939,
.008368,.010759,
.009,.010464,
.009571,.010064,
.010064,.009571,
.010464,.009,
.010759,.008368,
.010939,.007695,
.011,.007,
0.0*
%
%ADD38MACRO38*%
%AMMACRO33*
4,1,40,.013,-.017,
-.013,-.017,
-.013695,-.016939,
-.014368,-.016759,
-.015,-.016464,
-.015571,-.016064,
-.016064,-.015571,
-.016464,-.015,
-.016759,-.014368,
-.016939,-.013695,
-.017,-.013,
-.017,.013,
-.016939,.013695,
-.016759,.014368,
-.016464,.015,
-.016064,.015571,
-.015571,.016064,
-.015,.016464,
-.014368,.016759,
-.013695,.016939,
-.013,.017,
.013,.017,
.013695,.016939,
.014368,.016759,
.015,.016464,
.015571,.016064,
.016064,.015571,
.016464,.015,
.016759,.014368,
.016939,.013695,
.017,.013,
.017,-.013,
.016939,-.013695,
.016759,-.014368,
.016464,-.015,
.016064,-.015571,
.015571,-.016064,
.015,-.016464,
.014368,-.016759,
.013695,-.016939,
.013,-.017,
0.0*
%
%ADD33MACRO33*%
%AMMACRO21*
4,1,40,-.017,-.013,
-.017,.013,
-.016939,.013695,
-.016759,.014368,
-.016464,.015,
-.016064,.015571,
-.015571,.016064,
-.015,.016464,
-.014368,.016759,
-.013695,.016939,
-.013,.017,
.013,.017,
.013695,.016939,
.014368,.016759,
.015,.016464,
.015571,.016064,
.016064,.015571,
.016464,.015,
.016759,.014368,
.016939,.013695,
.017,.013,
.017,-.013,
.016939,-.013695,
.016759,-.014368,
.016464,-.015,
.016064,-.015571,
.015571,-.016064,
.015,-.016464,
.014368,-.016759,
.013695,-.016939,
.013,-.017,
-.013,-.017,
-.013695,-.016939,
-.014368,-.016759,
-.015,-.016464,
-.015571,-.016064,
-.016064,-.015571,
-.016464,-.015,
-.016759,-.014368,
-.016939,-.013695,
-.017,-.013,
0.0*
%
%ADD21MACRO21*%
%AMMACRO27*
4,1,20,-.0635,-.1075,
-.049,-.1075,
-.049,-.118,
-.0395,-.118,
-.0395,-.1075,
.0395,-.1075,
.0395,-.118,
.049,-.118,
.049,-.1075,
.0635,-.1075,
.0635,.1075,
.049,.1075,
.049,.118,
.0395,.118,
.0395,.1075,
-.0395,.1075,
-.0395,.118,
-.049,.118,
-.049,.1075,
-.0635,.1075,
-.0635,-.1075,
0.0*
%
%ADD27MACRO27*%
%AMMACRO31*
4,1,40,.012,.008,
.012,-.008,
.011939,-.008695,
.011759,-.009368,
.011464,-.01,
.011064,-.010571,
.010571,-.011064,
.01,-.011464,
.009368,-.011759,
.008695,-.011939,
.008,-.012,
-.008,-.012,
-.008695,-.011939,
-.009368,-.011759,
-.01,-.011464,
-.010571,-.011064,
-.011064,-.010571,
-.011464,-.01,
-.011759,-.009368,
-.011939,-.008695,
-.012,-.008,
-.012,.008,
-.011939,.008695,
-.011759,.009368,
-.011464,.01,
-.011064,.010571,
-.010571,.011064,
-.01,.011464,
-.009368,.011759,
-.008695,.011939,
-.008,.012,
.008,.012,
.008695,.011939,
.009368,.011759,
.01,.011464,
.010571,.011064,
.011064,.010571,
.011464,.01,
.011759,.009368,
.011939,.008695,
.012,.008,
0.0*
%
%ADD31MACRO31*%
%AMMACRO18*
4,1,40,-.007,.011,
.007,.011,
.007695,.010939,
.008368,.010759,
.009,.010464,
.009571,.010064,
.010064,.009571,
.010464,.009,
.010759,.008368,
.010939,.007695,
.011,.007,
.011,-.007,
.010939,-.007695,
.010759,-.008368,
.010464,-.009,
.010064,-.009571,
.009571,-.010064,
.009,-.010464,
.008368,-.010759,
.007695,-.010939,
.007,-.011,
-.007,-.011,
-.007695,-.010939,
-.008368,-.010759,
-.009,-.010464,
-.009571,-.010064,
-.010064,-.009571,
-.010464,-.009,
-.010759,-.008368,
-.010939,-.007695,
-.011,-.007,
-.011,.007,
-.010939,.007695,
-.010759,.008368,
-.010464,.009,
-.010064,.009571,
-.009571,.010064,
-.009,.010464,
-.008368,.010759,
-.007695,.010939,
-.007,.011,
0.0*
%
%ADD18MACRO18*%
%AMMACRO11*
4,1,40,.008,-.012,
-.008,-.012,
-.008695,-.011939,
-.009368,-.011759,
-.01,-.011464,
-.010571,-.011064,
-.011064,-.010571,
-.011464,-.01,
-.011759,-.009368,
-.011939,-.008695,
-.012,-.008,
-.012,.008,
-.011939,.008695,
-.011759,.009368,
-.011464,.01,
-.011064,.010571,
-.010571,.011064,
-.01,.011464,
-.009368,.011759,
-.008695,.011939,
-.008,.012,
.008,.012,
.008695,.011939,
.009368,.011759,
.01,.011464,
.010571,.011064,
.011064,.010571,
.011464,.01,
.011759,.009368,
.011939,.008695,
.012,.008,
.012,-.008,
.011939,-.008695,
.011759,-.009368,
.011464,-.01,
.011064,-.010571,
.010571,-.011064,
.01,-.011464,
.009368,-.011759,
.008695,-.011939,
.008,-.012,
0.0*
%
%ADD11MACRO11*%
%ADD56C,.02*%
%ADD57C,.006*%
G75*
%LPD*%
G75*
G36*
G01X804631Y1311185D02*
Y1302185D01*
X796031D01*
Y1311185D01*
X804631D01*
G37*
G36*
G01Y1322985D02*
Y1313985D01*
X796031D01*
Y1322985D01*
X804631D01*
G37*
G36*
G01X793231D02*
Y1313985D01*
X784631D01*
Y1322985D01*
X793231D01*
G37*
G36*
G01Y1311185D02*
Y1302185D01*
X784631D01*
Y1311185D01*
X793231D01*
G37*
G36*
G01X805101Y1353691D02*
Y1344691D01*
X796501D01*
Y1353691D01*
X805101D01*
G37*
G36*
G01Y1365491D02*
Y1356491D01*
X796501D01*
Y1365491D01*
X805101D01*
G37*
G36*
G01X793701D02*
Y1356491D01*
X785101D01*
Y1365491D01*
X793701D01*
G37*
G36*
G01Y1353691D02*
Y1344691D01*
X785101D01*
Y1353691D01*
X793701D01*
G37*
G36*
G01X804880Y1391359D02*
Y1382359D01*
X796280D01*
Y1391359D01*
X804880D01*
G37*
G36*
G01Y1403159D02*
Y1394159D01*
X796280D01*
Y1403159D01*
X804880D01*
G37*
G36*
G01X793480D02*
Y1394159D01*
X784880D01*
Y1403159D01*
X793480D01*
G37*
G36*
G01Y1391359D02*
Y1382359D01*
X784880D01*
Y1391359D01*
X793480D01*
G37*
G54D10*
X34900Y34200D03*
X40600Y1464400D03*
X1894200Y1471300D03*
G54D11*
X62263Y877225D03*
X160090Y439489D03*
X1702859Y442907D03*
X1777263Y877225D03*
G54D20*
X59963Y887525D03*
X157790Y449789D03*
X1021763Y1114199D03*
X996700Y1099000D03*
X978700Y1126800D03*
X1700559Y453207D03*
X1774963Y887525D03*
G54D21*
X32263Y878825D03*
X132190Y444689D03*
X127141Y904744D03*
X224968Y467008D03*
X969900Y1132600D03*
X1672859Y444507D03*
X1767737Y470426D03*
X1747263Y878825D03*
X1842141Y904744D03*
G54D12*
X62263Y880825D03*
X160090Y443089D03*
X1702859Y446507D03*
X1777263Y880825D03*
G54D30*
X161800Y853585D03*
Y878385D03*
Y917685D03*
Y892885D03*
X259627Y416249D03*
Y441049D03*
Y455549D03*
Y480349D03*
X1802496Y458967D03*
Y419667D03*
Y444467D03*
Y483767D03*
X1876600Y854185D03*
Y918285D03*
Y893485D03*
Y878985D03*
G54D31*
X125056Y909101D03*
X222883Y471365D03*
X950211Y1087648D03*
X993800Y1131000D03*
X1025500Y1122400D03*
X978300Y1084500D03*
X1765652Y474783D03*
X1840056Y909101D03*
G54D40*
X669470Y1467800D03*
X1022935Y1130078D03*
X1016645Y1106842D03*
G54D13*
X94463Y908025D03*
X192290Y470289D03*
X512746Y1442322D03*
X1735059Y473707D03*
X1809463Y908025D03*
G54D22*
X32263Y873225D03*
X132190Y439089D03*
X127141Y899144D03*
X224968Y461408D03*
X969900Y1127000D03*
X1672859Y438907D03*
X1767737Y464826D03*
X1747263Y873225D03*
X1842141Y899144D03*
G54D32*
X121456Y909101D03*
X219283Y471365D03*
X946611Y1087648D03*
X990200Y1131000D03*
X1021900Y1122400D03*
X974700Y1084500D03*
X1762052Y474783D03*
X1836456Y909101D03*
G54D23*
X56763Y874225D03*
Y881825D03*
X48763Y874225D03*
Y881825D03*
X40763Y874225D03*
Y881825D03*
X154590Y436489D03*
Y444089D03*
X146590Y436489D03*
Y444089D03*
X138590Y436489D03*
Y444089D03*
X175763Y895225D03*
Y902825D03*
X191763Y895225D03*
Y902825D03*
X183763Y895225D03*
Y902825D03*
X273590Y457489D03*
Y465089D03*
X289590Y457489D03*
Y465089D03*
X281590Y457489D03*
Y465089D03*
X944500Y1122200D03*
Y1129800D03*
X952500Y1122200D03*
Y1129800D03*
X960500Y1122200D03*
Y1129800D03*
X1697359Y439907D03*
Y447507D03*
X1689359Y439907D03*
Y447507D03*
X1681359Y439907D03*
Y447507D03*
X1816338Y460823D03*
Y468423D03*
X1771763Y874225D03*
Y881825D03*
X1763763Y874225D03*
Y881825D03*
X1755763Y874225D03*
Y881825D03*
X1831598Y460827D03*
Y468427D03*
X1823987Y460819D03*
Y468419D03*
X1890763Y895225D03*
Y902825D03*
X1906763Y895225D03*
Y902825D03*
X1898763Y895225D03*
Y902825D03*
G54D50*
X1002000Y1144000D03*
X1013000D03*
G54D41*
X669470Y1464200D03*
X1022935Y1126478D03*
X1016645Y1103242D03*
G54D14*
X98063Y908025D03*
X195890Y470289D03*
X516346Y1442322D03*
X1738659Y473707D03*
X1813063Y908025D03*
G54D33*
X104226Y904041D03*
X202053Y466305D03*
X1744822Y469723D03*
X1819226Y904041D03*
G54D42*
X859086Y1290016D03*
Y1300984D03*
X842500Y1404984D03*
Y1394016D03*
X860000Y1404984D03*
Y1394016D03*
X871589Y1290016D03*
Y1300984D03*
X884060Y1290048D03*
Y1301016D03*
X876500Y1404984D03*
Y1394016D03*
G54D24*
X64563Y894025D03*
X56963D03*
X32463Y866525D03*
X40063D03*
X162390Y456289D03*
X154790D03*
X133290Y429089D03*
X140890D03*
X711500Y1463600D03*
X719100D03*
X817800Y1333000D03*
X810200D03*
X817800Y1296000D03*
X810200D03*
X817800Y1371500D03*
X810200D03*
X951461Y1093799D03*
X943861D03*
X951300Y1101700D03*
X943700D03*
X951400Y1109600D03*
X943800D03*
X994800Y1136500D03*
X987200D03*
X994800Y1144500D03*
X987200D03*
X960200Y1082500D03*
X967800D03*
X1705159Y459707D03*
X1697559D03*
X1673059Y432207D03*
X1680659D03*
X1779563Y894025D03*
X1771963D03*
X1747463Y866525D03*
X1755063D03*
G54D15*
X88941Y905416D03*
X186768Y467680D03*
X121736Y903674D03*
X219563Y465938D03*
X512849Y1438455D03*
X974200Y1130000D03*
X1762332Y469356D03*
X1729537Y471098D03*
X1803941Y905416D03*
X1836736Y903674D03*
G54D51*
X1001687Y1111499D03*
G54D52*
X1004640Y1117605D03*
X998734D03*
Y1105393D03*
X1004640D03*
G54D43*
X809631Y1305085D03*
Y1310085D03*
Y1315085D03*
Y1320085D03*
X810101Y1347591D03*
Y1352591D03*
Y1357591D03*
Y1362591D03*
X809880Y1385259D03*
Y1390259D03*
Y1395259D03*
Y1400259D03*
G54D16*
X88941Y902016D03*
X186768Y464280D03*
X121736Y900274D03*
X219563Y462538D03*
X512849Y1435055D03*
X974200Y1126600D03*
X1762332Y465956D03*
X1729537Y467698D03*
X1803941Y902016D03*
X1836736Y900274D03*
G54D25*
X83163Y905075D03*
X180990Y467339D03*
X1024284Y1103036D03*
X1723759Y470757D03*
X1798163Y905075D03*
G54D34*
X109826Y904041D03*
X207653Y466305D03*
X1750422Y469723D03*
X1824826Y904041D03*
G54D17*
X98000Y904300D03*
X195827Y466564D03*
X662000Y1464000D03*
Y1468000D03*
Y1453500D03*
Y1457500D03*
X1008689Y1092328D03*
X1027687Y1109799D03*
X1738596Y469982D03*
X1812900Y904300D03*
G54D53*
X1002671Y1117555D03*
X1000703D03*
Y1105443D03*
X1002671D03*
G54D44*
X962648Y1101699D03*
X984534D03*
G54D35*
X143111Y874400D03*
X108489D03*
X240938Y436664D03*
X206316D03*
X1783707Y440082D03*
X1749085D03*
X1823489Y874400D03*
X1858111D03*
G54D26*
X83163Y902375D03*
X180990Y464639D03*
X1024284Y1100336D03*
X1723759Y468057D03*
X1798163Y902375D03*
G54D18*
X94600Y904300D03*
X192427Y466564D03*
X658600Y1464000D03*
Y1468000D03*
Y1453500D03*
Y1457500D03*
X1005289Y1092328D03*
X1024287Y1109799D03*
X1735196Y469982D03*
X1809500Y904300D03*
G54D27*
X85000Y885500D03*
X182827Y447764D03*
X1725596Y451182D03*
X1800000Y885500D03*
G54D54*
X995581Y1114452D03*
Y1108546D03*
X1007793D03*
Y1114452D03*
G54D36*
X501699Y1429055D03*
Y1438055D03*
G54D45*
X1021393Y1118601D03*
G54D55*
X995631Y1112483D03*
Y1110515D03*
X1007743D03*
Y1112483D03*
G54D28*
X75357Y895343D03*
Y893374D03*
Y891406D03*
Y889437D03*
Y887469D03*
Y885500D03*
Y883531D03*
Y881563D03*
Y879594D03*
Y877626D03*
Y875657D03*
X94643D03*
Y877626D03*
Y879594D03*
Y881563D03*
Y883531D03*
Y885500D03*
Y887469D03*
Y889437D03*
Y891406D03*
Y893374D03*
Y895343D03*
X173184Y457607D03*
Y455638D03*
Y453670D03*
Y451701D03*
Y449733D03*
Y447764D03*
Y445795D03*
Y443827D03*
Y441858D03*
Y439890D03*
Y437921D03*
X192470D03*
Y439890D03*
Y441858D03*
Y443827D03*
Y445795D03*
Y447764D03*
Y449733D03*
Y451701D03*
Y453670D03*
Y455638D03*
Y457607D03*
X1715953Y461025D03*
Y459056D03*
Y457088D03*
Y455119D03*
Y453151D03*
Y451182D03*
Y449213D03*
Y447245D03*
Y445276D03*
Y443308D03*
Y441339D03*
X1735239D03*
Y443308D03*
Y445276D03*
Y447245D03*
Y449213D03*
Y451182D03*
Y453151D03*
Y455119D03*
Y457088D03*
Y459056D03*
Y461025D03*
X1790357Y895343D03*
Y893374D03*
Y891406D03*
Y889437D03*
Y887469D03*
Y885500D03*
Y883531D03*
Y881563D03*
Y879594D03*
Y877626D03*
Y875657D03*
X1809643D03*
Y877626D03*
Y879594D03*
Y881563D03*
Y883531D03*
Y885500D03*
Y887469D03*
Y889437D03*
Y891406D03*
Y893374D03*
Y895343D03*
G54D46*
X1024793Y1118601D03*
G54D19*
X65563Y887525D03*
X163390Y449789D03*
X1027363Y1114199D03*
X1002300Y1099000D03*
X984300Y1126800D03*
X1706159Y453207D03*
X1780563Y887525D03*
G54D37*
X512799Y1429105D03*
X516674Y1421605D03*
X508924D03*
G54D56*
G01X466941Y-145664D02*
Y-225664D01*
G01D02*
X1593241D01*
G01X462941Y-129664D02*
G02I-12000J0D01*
G01X457791D02*
G02I-6850J0D01*
G01X450941Y-145664D02*
Y-113664D01*
G01X466941Y-129664D02*
X434941D01*
G01X466941Y-145664D02*
X1593241D01*
G01X466941Y-181164D02*
X1593241D01*
G01X805741Y-145664D02*
Y-225664D01*
G01X943241Y-145664D02*
Y-225664D01*
G01X1058241Y-145664D02*
Y-225664D01*
G01X1225741Y-145664D02*
Y-225664D01*
G01X1395741Y-145664D02*
Y-225664D01*
G01X1593241Y-145664D02*
Y-225664D01*
G01X1621241Y-129664D02*
G02I-12000J0D01*
G01X1616091D02*
G02I-6850J0D01*
G01X1609241Y-145664D02*
Y-113664D01*
G01X1625241Y-129664D02*
X1593241D01*
G54D38*
X516898Y1435021D03*
X1026700Y1130200D03*
X1013231Y1094671D03*
X986500Y1118800D03*
G54D29*
X47329Y895302D03*
X48763Y900772D03*
X140716Y453101D03*
X146590Y463036D03*
X192425Y869073D03*
X126263Y914025D03*
X103263Y909525D03*
X112763Y912025D03*
X120496Y1405549D03*
X125469Y1373872D03*
X200879Y470744D03*
X213590Y474289D03*
X224090Y476289D03*
X201778Y878425D03*
X279700Y1428000D03*
X291450Y439719D03*
X298690Y441316D03*
X296183Y433389D03*
X298486Y454996D03*
X508196Y1434276D03*
X508099Y1439755D03*
X847881Y1198981D03*
X810000Y1290500D03*
X810221Y1339832D03*
X810000Y1377500D03*
X943904Y372485D03*
X896476Y502611D03*
X913276Y501747D03*
X950000Y1081000D03*
X941456Y1182512D03*
X951723Y1177569D03*
X873200Y1208700D03*
X942100Y1193300D03*
X914031Y1243291D03*
X1038179Y413863D03*
X1022646Y401202D03*
X1021469Y390508D03*
X1047434Y429008D03*
X977047Y393217D03*
X996452Y404314D03*
X1027862Y414122D03*
X1004412Y559568D03*
X995316Y554256D03*
X978415Y547627D03*
X968979Y542300D03*
X970000Y1121500D03*
X1000000Y1094500D03*
X973500Y1080500D03*
X1013000Y1108500D03*
X978500Y1122000D03*
X990200Y1118300D03*
X988800Y1126800D03*
X1017700Y1118304D03*
X996900Y1124500D03*
X1016300Y1113500D03*
X982227Y1150350D03*
X1071421Y443932D03*
X1074279Y407249D03*
X1059563Y425123D03*
X1110767Y1309112D03*
X1184500Y570000D03*
X1198184Y740895D03*
X1192158Y736695D03*
X1197842Y732495D03*
X1192853Y728295D03*
X1198213Y724095D03*
X1192568Y719895D03*
X1185718Y1333821D03*
X1160612Y1401773D03*
X1247682Y1421608D03*
X1688216Y461478D03*
X1689359Y466454D03*
X1817496Y437282D03*
X1743859Y475207D03*
X1766859Y479707D03*
X1754525Y478316D03*
X1762442Y895401D03*
X1763763Y900772D03*
X1825896Y440582D03*
X1835508Y444107D03*
X1835092Y435418D03*
X1907800Y871200D03*
X1841263Y914025D03*
X1827863Y912525D03*
X1818263Y909525D03*
G54D47*
X1031000Y1099500D03*
G54D57*
G01X489037Y-206331D02*
X489911Y-205456D01*
X490566Y-203998D01*
X491003Y-201955D01*
X490566Y-200206D01*
X489693Y-199039D01*
X488164Y-198164D01*
X482269D01*
Y-215664D01*
X489474D01*
X491003Y-214498D01*
X491876Y-212747D01*
X492313Y-210706D01*
X491876Y-208664D01*
X490566Y-206914D01*
X489037Y-206331D01*
X482269D01*
G01X501734Y-215664D02*
Y-203998D01*
G01Y-206331D02*
X502826Y-205164D01*
X503918Y-204289D01*
X505446Y-203998D01*
X506537Y-204289D01*
X507848Y-205164D01*
G01X517706Y-220914D02*
X519016Y-221497D01*
X520763Y-220914D01*
X521854Y-219748D01*
X522728Y-218289D01*
X524037Y-213623D01*
X526876Y-203998D01*
G01X519889D02*
X524037Y-213623D01*
G01X543284Y-205456D02*
X541756Y-204289D01*
X540446Y-203998D01*
X538699Y-204581D01*
X537389Y-205747D01*
X536516Y-207789D01*
X536297Y-209831D01*
X536516Y-211873D01*
X537389Y-213623D01*
X538699Y-215081D01*
X540446Y-215664D01*
X541974Y-215081D01*
X543284Y-213914D01*
G01X554016Y-207789D02*
X561003D01*
X560348Y-205747D01*
X559256Y-204581D01*
X557728Y-203998D01*
X556199Y-204289D01*
X554889Y-205164D01*
X554016Y-207206D01*
X553579Y-208956D01*
Y-210706D01*
X554016Y-212456D01*
X555108Y-214206D01*
X556418Y-215372D01*
X557946Y-215664D01*
X559474Y-215081D01*
X561003Y-213331D01*
G01X597094Y-199623D02*
X595784Y-198747D01*
X594256Y-198164D01*
X592509D01*
X590544Y-199039D01*
X589016Y-200497D01*
X587924Y-202248D01*
X587051Y-205164D01*
X586832Y-207789D01*
X587269Y-210414D01*
X587924Y-212164D01*
X589234Y-213914D01*
X590763Y-215081D01*
X592291Y-215664D01*
X593819D01*
X595348Y-215081D01*
X596658Y-214206D01*
X597750Y-213040D01*
G01X613721Y-215664D02*
Y-203998D01*
G01Y-206039D02*
X612848Y-204873D01*
X611537Y-204289D01*
X610009Y-203998D01*
X608481Y-204581D01*
X607171Y-205747D01*
X606297Y-207497D01*
X605861Y-209831D01*
X606297Y-212164D01*
X607171Y-213914D01*
X608481Y-215081D01*
X610009Y-215664D01*
X611537Y-215372D01*
X612848Y-214498D01*
X613721Y-213331D01*
G01X623579Y-215664D02*
Y-203998D01*
G01Y-206914D02*
X624453Y-205456D01*
X625763Y-204289D01*
X627509Y-203998D01*
X629037Y-204289D01*
X630348Y-205456D01*
X631003Y-207497D01*
Y-215664D01*
G01X640206Y-220914D02*
X641516Y-221497D01*
X643263Y-220914D01*
X644354Y-219748D01*
X645228Y-218289D01*
X646537Y-213623D01*
X649376Y-203998D01*
G01X642389D02*
X646537Y-213623D01*
G01X662291Y-215664D02*
X660981Y-215372D01*
X659671Y-214206D01*
X658797Y-212164D01*
X658361Y-209831D01*
X658797Y-207497D01*
X659671Y-205456D01*
X660981Y-204289D01*
X662291Y-203998D01*
X663601Y-204289D01*
X664911Y-205456D01*
X665784Y-207497D01*
X666003Y-209831D01*
X665784Y-212164D01*
X664911Y-214206D01*
X663601Y-215372D01*
X662291Y-215664D01*
G01X676079D02*
Y-203998D01*
G01Y-206914D02*
X676953Y-205456D01*
X678263Y-204289D01*
X680009Y-203998D01*
X681537Y-204289D01*
X682848Y-205456D01*
X683503Y-207497D01*
Y-215664D01*
G01X710424D02*
Y-198164D01*
X715883D01*
X717629Y-199039D01*
X718721Y-200206D01*
X719158Y-202539D01*
X718721Y-204873D01*
X717411Y-206331D01*
X715883Y-207206D01*
X710424D01*
G01X715883D02*
X719158Y-215664D01*
G01X732291Y-216247D02*
X731854Y-215956D01*
Y-215372D01*
X732291Y-215081D01*
X732728Y-215372D01*
Y-215956D01*
X732291Y-216247D01*
G01X744988Y-215664D02*
Y-198164D01*
X749354D01*
X751101Y-199039D01*
X752411Y-200206D01*
X753503Y-201955D01*
X754376Y-203998D01*
X754594Y-206914D01*
X754376Y-209831D01*
X753503Y-211873D01*
X752411Y-213623D01*
X751101Y-214789D01*
X749354Y-215664D01*
X744988D01*
G01X762924D02*
Y-198164D01*
X768164D01*
X769911Y-199039D01*
X771221Y-201081D01*
X771658Y-203414D01*
X771221Y-205747D01*
X770129Y-207497D01*
X768164Y-208373D01*
X762924D01*
G01X786537Y-206331D02*
X787411Y-205456D01*
X788066Y-203998D01*
X788503Y-201955D01*
X788066Y-200206D01*
X787193Y-199039D01*
X785664Y-198164D01*
X779769D01*
Y-215664D01*
X786974D01*
X788503Y-214498D01*
X789376Y-212747D01*
X789813Y-210706D01*
X789376Y-208664D01*
X788066Y-206914D01*
X786537Y-206331D01*
X779769D01*
G01X595364Y-170664D02*
Y-153164D01*
X601041Y-167747D01*
X606718Y-153164D01*
Y-170664D01*
G01X618541D02*
X617231Y-170372D01*
X615921Y-169206D01*
X615047Y-167164D01*
X614611Y-164831D01*
X615047Y-162497D01*
X615921Y-160456D01*
X617231Y-159289D01*
X618541Y-158998D01*
X619851Y-159289D01*
X621161Y-160456D01*
X622034Y-162497D01*
X622253Y-164831D01*
X622034Y-167164D01*
X621161Y-169206D01*
X619851Y-170372D01*
X618541Y-170664D01*
G01X639971Y-153164D02*
Y-170664D01*
G01Y-168040D02*
X639098Y-169498D01*
X637787Y-170372D01*
X636259Y-170664D01*
X634513Y-170081D01*
X633203Y-168623D01*
X632329Y-166873D01*
X632111Y-164831D01*
X632329Y-162789D01*
X633203Y-161039D01*
X634513Y-159581D01*
X636259Y-158998D01*
X637787Y-159289D01*
X638879Y-159873D01*
X639971Y-161039D01*
G01X650266Y-162789D02*
X657253D01*
X656598Y-160747D01*
X655506Y-159581D01*
X653978Y-158998D01*
X652449Y-159289D01*
X651139Y-160164D01*
X650266Y-162206D01*
X649829Y-163956D01*
Y-165706D01*
X650266Y-167456D01*
X651358Y-169206D01*
X652668Y-170372D01*
X654196Y-170664D01*
X655724Y-170081D01*
X657253Y-168331D01*
G01X671041Y-170664D02*
Y-153164D01*
G01X839441Y-215664D02*
Y-198164D01*
X836821Y-201664D01*
G01Y-215664D02*
X842061D01*
G01X852793Y-208373D02*
X854321Y-206331D01*
X855631Y-205164D01*
X857378Y-204581D01*
X858906Y-205164D01*
X859998Y-206331D01*
X860871Y-208081D01*
X861089Y-210122D01*
X860871Y-211873D01*
X859998Y-213623D01*
X858687Y-215081D01*
X857159Y-215664D01*
X855413Y-215081D01*
X853884Y-213331D01*
X853011Y-210706D01*
X852793Y-207789D01*
X853229Y-203998D01*
X853884Y-201955D01*
X854976Y-199914D01*
X856504Y-198456D01*
X858033Y-198164D01*
X859561Y-198747D01*
X860653Y-200206D01*
G01X869638Y-212164D02*
X870947Y-214206D01*
X872694Y-215372D01*
X874659Y-215664D01*
X876406Y-215372D01*
X878153Y-213914D01*
X879244Y-212164D01*
X879463Y-210414D01*
X879026Y-208373D01*
X877498Y-206914D01*
X875969Y-206331D01*
X874004D01*
G01X875969D02*
X877279Y-205456D01*
X878371Y-203998D01*
X878808Y-202248D01*
X878371Y-200497D01*
X877279Y-199039D01*
X875314Y-198164D01*
X873349Y-198456D01*
X871384Y-199623D01*
G01X891941Y-215664D02*
Y-198164D01*
X889321Y-201664D01*
G01Y-215664D02*
X894561D01*
G01X909004D02*
X909441Y-211873D01*
X910096Y-208664D01*
X910969Y-205747D01*
X912061Y-202539D01*
X913808Y-198164D01*
X905074D01*
G01X826324Y-170664D02*
Y-153164D01*
X831564D01*
X833311Y-154039D01*
X834621Y-156081D01*
X835058Y-158414D01*
X834621Y-160747D01*
X833529Y-162497D01*
X831564Y-163373D01*
X826324D01*
G01X852994Y-154623D02*
X851684Y-153747D01*
X850156Y-153164D01*
X848409D01*
X846444Y-154039D01*
X844916Y-155497D01*
X843824Y-157248D01*
X842951Y-160164D01*
X842732Y-162789D01*
X843169Y-165414D01*
X843824Y-167164D01*
X845134Y-168914D01*
X846663Y-170081D01*
X848191Y-170664D01*
X849719D01*
X851248Y-170081D01*
X852558Y-169206D01*
X853650Y-168040D01*
G01X867437Y-161331D02*
X868311Y-160456D01*
X868966Y-158998D01*
X869403Y-156955D01*
X868966Y-155206D01*
X868093Y-154039D01*
X866564Y-153164D01*
X860669D01*
Y-170664D01*
X867874D01*
X869403Y-169498D01*
X870276Y-167747D01*
X870713Y-165706D01*
X870276Y-163664D01*
X868966Y-161914D01*
X867437Y-161331D01*
X860669D01*
G01X876641Y-176497D02*
X889741D01*
G01X895669Y-170664D02*
Y-153164D01*
X905713Y-170664D01*
Y-153164D01*
G01X918191Y-170664D02*
X916444Y-170372D01*
X914916Y-169206D01*
X913606Y-167456D01*
X912732Y-165414D01*
X912296Y-163081D01*
Y-160747D01*
X912732Y-158414D01*
X913606Y-156372D01*
X914916Y-154623D01*
X916444Y-153456D01*
X918191Y-153164D01*
X919937Y-153456D01*
X921466Y-154623D01*
X922776Y-156372D01*
X923650Y-158414D01*
X924086Y-160747D01*
Y-163081D01*
X923650Y-165414D01*
X922776Y-167456D01*
X921466Y-169206D01*
X919937Y-170372D01*
X918191Y-170664D01*
G01X1000741Y-215664D02*
Y-198164D01*
X998121Y-201664D01*
G01Y-215664D02*
X1003361D01*
G01X969032Y-153164D02*
X974491Y-170664D01*
X979950Y-153164D01*
G01X996358Y-170664D02*
X987624D01*
Y-153164D01*
X996358D01*
G01X992864Y-161622D02*
X987624D01*
G01X1005124Y-170664D02*
Y-153164D01*
X1010583D01*
X1012329Y-154039D01*
X1013421Y-155206D01*
X1013858Y-157539D01*
X1013421Y-159873D01*
X1012111Y-161331D01*
X1010583Y-162206D01*
X1005124D01*
G01X1010583D02*
X1013858Y-170664D01*
G01X1026991Y-171247D02*
X1026554Y-170956D01*
Y-170372D01*
X1026991Y-170081D01*
X1027428Y-170372D01*
Y-170956D01*
X1026991Y-171247D01*
G01X1166445Y-206331D02*
X1165571Y-205456D01*
X1164916Y-203998D01*
X1164479Y-201955D01*
X1164916Y-200206D01*
X1165789Y-199039D01*
X1167318Y-198164D01*
X1173213D01*
Y-215664D01*
X1166008D01*
X1164479Y-214498D01*
X1163606Y-212747D01*
X1163169Y-210706D01*
X1163606Y-208664D01*
X1164916Y-206914D01*
X1166445Y-206331D01*
X1173213D01*
G01X1155276Y-213331D02*
X1153529Y-214789D01*
X1151564Y-215664D01*
X1149818D01*
X1148071Y-214789D01*
X1146761Y-213331D01*
X1146106Y-211289D01*
X1146543Y-209248D01*
X1147634Y-207497D01*
X1149599Y-206331D01*
X1152219Y-205747D01*
X1153748Y-204581D01*
X1154403Y-202539D01*
X1153966Y-200497D01*
X1152874Y-199039D01*
X1151346Y-198164D01*
X1149818D01*
X1148289Y-198747D01*
X1146979Y-200206D01*
G01X1138868Y-215664D02*
Y-198164D01*
X1133191Y-212747D01*
X1127514Y-198164D01*
Y-215664D01*
G01X1120494D02*
Y-198164D01*
X1116128D01*
X1114381Y-199039D01*
X1113071Y-200206D01*
X1111979Y-201955D01*
X1111106Y-203998D01*
X1110888Y-206914D01*
X1111106Y-209831D01*
X1111979Y-211873D01*
X1113071Y-213623D01*
X1114381Y-214789D01*
X1116128Y-215664D01*
X1120494D01*
G01X1102574Y-153164D02*
Y-170664D01*
X1111308D01*
G01X1128371D02*
Y-158998D01*
G01Y-161039D02*
X1127498Y-159873D01*
X1126187Y-159289D01*
X1124659Y-158998D01*
X1123131Y-159581D01*
X1121821Y-160747D01*
X1120947Y-162497D01*
X1120511Y-164831D01*
X1120947Y-167164D01*
X1121821Y-168914D01*
X1123131Y-170081D01*
X1124659Y-170664D01*
X1126187Y-170372D01*
X1127498Y-169498D01*
X1128371Y-168331D01*
G01X1137356Y-175914D02*
X1138666Y-176497D01*
X1140413Y-175914D01*
X1141504Y-174748D01*
X1142378Y-173289D01*
X1143687Y-168623D01*
X1146526Y-158998D01*
G01X1139539D02*
X1143687Y-168623D01*
G01X1156166Y-162789D02*
X1163153D01*
X1162498Y-160747D01*
X1161406Y-159581D01*
X1159878Y-158998D01*
X1158349Y-159289D01*
X1157039Y-160164D01*
X1156166Y-162206D01*
X1155729Y-163956D01*
Y-165706D01*
X1156166Y-167456D01*
X1157258Y-169206D01*
X1158568Y-170372D01*
X1160096Y-170664D01*
X1161624Y-170081D01*
X1163153Y-168331D01*
G01X1173884Y-170664D02*
Y-158998D01*
G01Y-161331D02*
X1174976Y-160164D01*
X1176068Y-159289D01*
X1177596Y-158998D01*
X1178687Y-159289D01*
X1179998Y-160164D01*
G01X1244688Y-170664D02*
Y-153164D01*
X1249054D01*
X1250801Y-154039D01*
X1252111Y-155206D01*
X1253203Y-156955D01*
X1254076Y-158998D01*
X1254294Y-161914D01*
X1254076Y-164831D01*
X1253203Y-166873D01*
X1252111Y-168623D01*
X1250801Y-169789D01*
X1249054Y-170664D01*
X1244688D01*
G01X1263716Y-162789D02*
X1270703D01*
X1270048Y-160747D01*
X1268956Y-159581D01*
X1267428Y-158998D01*
X1265899Y-159289D01*
X1264589Y-160164D01*
X1263716Y-162206D01*
X1263279Y-163956D01*
Y-165706D01*
X1263716Y-167456D01*
X1264808Y-169206D01*
X1266118Y-170372D01*
X1267646Y-170664D01*
X1269174Y-170081D01*
X1270703Y-168331D01*
G01X1281216Y-168623D02*
X1282308Y-169789D01*
X1283836Y-170664D01*
X1285146D01*
X1286456Y-170081D01*
X1287329Y-169206D01*
X1287766Y-168040D01*
X1287548Y-166289D01*
X1286674Y-165414D01*
X1282744Y-163664D01*
X1281871Y-161622D01*
X1282308Y-160164D01*
X1283181Y-159289D01*
X1284491Y-158998D01*
X1285801Y-159289D01*
X1287111Y-160164D01*
G01X1301991Y-158998D02*
Y-170664D01*
G01Y-154331D02*
X1301554Y-154039D01*
Y-153456D01*
X1301991Y-153164D01*
X1302428Y-153456D01*
Y-154039D01*
X1301991Y-154331D01*
G01X1316434Y-175039D02*
X1317963Y-176206D01*
X1319709Y-176497D01*
X1321237Y-176206D01*
X1322548Y-174748D01*
X1323421Y-172706D01*
Y-158998D01*
G01Y-161331D02*
X1322548Y-160164D01*
X1321237Y-159289D01*
X1319709Y-158998D01*
X1317963Y-159581D01*
X1316871Y-160747D01*
X1315997Y-162789D01*
X1315561Y-164831D01*
X1315779Y-166581D01*
X1316653Y-168623D01*
X1317963Y-170081D01*
X1319709Y-170664D01*
X1321019Y-170372D01*
X1322548Y-169206D01*
X1323421Y-168040D01*
G01X1333279Y-170664D02*
Y-158998D01*
G01Y-161914D02*
X1334153Y-160456D01*
X1335463Y-159289D01*
X1337209Y-158998D01*
X1338737Y-159289D01*
X1340048Y-160456D01*
X1340703Y-162497D01*
Y-170664D01*
G01X1351216Y-162789D02*
X1358203D01*
X1357548Y-160747D01*
X1356456Y-159581D01*
X1354928Y-158998D01*
X1353399Y-159289D01*
X1352089Y-160164D01*
X1351216Y-162206D01*
X1350779Y-163956D01*
Y-165706D01*
X1351216Y-167456D01*
X1352308Y-169206D01*
X1353618Y-170372D01*
X1355146Y-170664D01*
X1356674Y-170081D01*
X1358203Y-168331D01*
G01X1368934Y-170664D02*
Y-158998D01*
G01Y-161331D02*
X1370026Y-160164D01*
X1371118Y-159289D01*
X1372646Y-158998D01*
X1373737Y-159289D01*
X1375048Y-160164D01*
G01X1266991Y-215664D02*
X1265244Y-215372D01*
X1263716Y-214206D01*
X1262406Y-212456D01*
X1261532Y-210414D01*
X1261096Y-208081D01*
Y-205747D01*
X1261532Y-203414D01*
X1262406Y-201372D01*
X1263716Y-199623D01*
X1265244Y-198456D01*
X1266991Y-198164D01*
X1268737Y-198456D01*
X1270266Y-199623D01*
X1271576Y-201372D01*
X1272450Y-203414D01*
X1272886Y-205747D01*
Y-208081D01*
X1272450Y-210414D01*
X1271576Y-212456D01*
X1270266Y-214206D01*
X1268737Y-215372D01*
X1266991Y-215664D01*
G01X1268737Y-210997D02*
X1271358Y-215664D01*
G01X1279688Y-198164D02*
Y-210706D01*
X1280561Y-213331D01*
X1282308Y-215081D01*
X1284491Y-215664D01*
X1286674Y-215081D01*
X1288421Y-213331D01*
X1289294Y-210706D01*
Y-198164D01*
G01X1299371D02*
X1304611D01*
G01X1301991D02*
Y-215664D01*
G01X1299371D02*
X1304611D01*
G01X1314469D02*
Y-198164D01*
X1324513Y-215664D01*
Y-198164D01*
G01X1341794Y-199623D02*
X1340484Y-198747D01*
X1338956Y-198164D01*
X1337209D01*
X1335244Y-199039D01*
X1333716Y-200497D01*
X1332624Y-202248D01*
X1331751Y-205164D01*
X1331532Y-207789D01*
X1331969Y-210414D01*
X1332624Y-212164D01*
X1333934Y-213914D01*
X1335463Y-215081D01*
X1336991Y-215664D01*
X1338519D01*
X1340048Y-215081D01*
X1341358Y-214206D01*
X1342450Y-213040D01*
G01X1354491Y-215664D02*
Y-207789D01*
X1350124Y-198164D01*
G01X1358858D02*
X1354491Y-207789D01*
G01X1415691Y-198164D02*
X1413944Y-198747D01*
X1412634Y-200206D01*
X1411761Y-201955D01*
X1411106Y-204289D01*
X1410888Y-206914D01*
X1411106Y-209539D01*
X1411761Y-211873D01*
X1412634Y-213623D01*
X1413944Y-215081D01*
X1415691Y-215664D01*
X1417437Y-215081D01*
X1418748Y-213623D01*
X1419621Y-211873D01*
X1420276Y-209539D01*
X1420494Y-206914D01*
X1420276Y-204289D01*
X1419621Y-201955D01*
X1418748Y-200206D01*
X1417437Y-198747D01*
X1415691Y-198164D01*
G01X1429043Y-208373D02*
X1430571Y-206331D01*
X1431881Y-205164D01*
X1433628Y-204581D01*
X1435156Y-205164D01*
X1436248Y-206331D01*
X1437121Y-208081D01*
X1437339Y-210122D01*
X1437121Y-211873D01*
X1436248Y-213623D01*
X1434937Y-215081D01*
X1433409Y-215664D01*
X1431663Y-215081D01*
X1430134Y-213331D01*
X1429261Y-210706D01*
X1429043Y-207789D01*
X1429479Y-203998D01*
X1430134Y-201955D01*
X1431226Y-199914D01*
X1432754Y-198456D01*
X1434283Y-198164D01*
X1435811Y-198747D01*
X1436903Y-200206D01*
G01X1446761Y-216247D02*
X1454621Y-198164D01*
G01X1468191D02*
X1466444Y-198747D01*
X1465134Y-200206D01*
X1464261Y-201955D01*
X1463606Y-204289D01*
X1463388Y-206914D01*
X1463606Y-209539D01*
X1464261Y-211873D01*
X1465134Y-213623D01*
X1466444Y-215081D01*
X1468191Y-215664D01*
X1469937Y-215081D01*
X1471248Y-213623D01*
X1472121Y-211873D01*
X1472776Y-209539D01*
X1472994Y-206914D01*
X1472776Y-204289D01*
X1472121Y-201955D01*
X1471248Y-200206D01*
X1469937Y-198747D01*
X1468191Y-198164D01*
G01X1481979Y-213623D02*
X1483508Y-215081D01*
X1485254Y-215664D01*
X1487001Y-215081D01*
X1488529Y-213331D01*
X1489621Y-210706D01*
X1490058Y-208081D01*
Y-204873D01*
X1489621Y-202248D01*
X1488529Y-199914D01*
X1487219Y-198747D01*
X1485691Y-198164D01*
X1483944Y-198747D01*
X1482634Y-199914D01*
X1481761Y-201664D01*
X1481324Y-203998D01*
X1481761Y-206039D01*
X1482853Y-208081D01*
X1484163Y-209248D01*
X1485691Y-209539D01*
X1487437Y-208956D01*
X1488748Y-207497D01*
X1490058Y-204873D01*
G01X1499261Y-216247D02*
X1507121Y-198164D01*
G01X1516543Y-201081D02*
X1517853Y-199331D01*
X1519381Y-198456D01*
X1521128Y-198164D01*
X1523311Y-198747D01*
X1524839Y-200206D01*
X1525276Y-201955D01*
X1525058Y-203706D01*
X1524184Y-205164D01*
X1519818Y-208081D01*
X1517853Y-210122D01*
X1516543Y-213040D01*
X1516106Y-215664D01*
X1525276D01*
G01X1538191Y-198164D02*
X1536444Y-198747D01*
X1535134Y-200206D01*
X1534261Y-201955D01*
X1533606Y-204289D01*
X1533388Y-206914D01*
X1533606Y-209539D01*
X1534261Y-211873D01*
X1535134Y-213623D01*
X1536444Y-215081D01*
X1538191Y-215664D01*
X1539937Y-215081D01*
X1541248Y-213623D01*
X1542121Y-211873D01*
X1542776Y-209539D01*
X1542994Y-206914D01*
X1542776Y-204289D01*
X1542121Y-201955D01*
X1541248Y-200206D01*
X1539937Y-198747D01*
X1538191Y-198164D01*
G01X1555691Y-215664D02*
Y-198164D01*
X1553071Y-201664D01*
G01Y-215664D02*
X1558311D01*
G01X1572754D02*
X1573191Y-211873D01*
X1573846Y-208664D01*
X1574719Y-205747D01*
X1575811Y-202539D01*
X1577558Y-198164D01*
X1568824D01*
G01X1463388Y-170664D02*
Y-153164D01*
X1467754D01*
X1469501Y-154039D01*
X1470811Y-155206D01*
X1471903Y-156955D01*
X1472776Y-158998D01*
X1472994Y-161914D01*
X1472776Y-164831D01*
X1471903Y-166873D01*
X1470811Y-168623D01*
X1469501Y-169789D01*
X1467754Y-170664D01*
X1463388D01*
G01X1489621D02*
Y-158998D01*
G01Y-161039D02*
X1488748Y-159873D01*
X1487437Y-159289D01*
X1485909Y-158998D01*
X1484381Y-159581D01*
X1483071Y-160747D01*
X1482197Y-162497D01*
X1481761Y-164831D01*
X1482197Y-167164D01*
X1483071Y-168914D01*
X1484381Y-170081D01*
X1485909Y-170664D01*
X1487437Y-170372D01*
X1488748Y-169498D01*
X1489621Y-168331D01*
G01X1503191Y-153164D02*
Y-170664D01*
G01X1500134Y-158998D02*
X1506248D01*
G01X1517416Y-162789D02*
X1524403D01*
X1523748Y-160747D01*
X1522656Y-159581D01*
X1521128Y-158998D01*
X1519599Y-159289D01*
X1518289Y-160164D01*
X1517416Y-162206D01*
X1516979Y-163956D01*
Y-165706D01*
X1517416Y-167456D01*
X1518508Y-169206D01*
X1519818Y-170372D01*
X1521346Y-170664D01*
X1522874Y-170081D01*
X1524403Y-168331D01*
G01X0Y3937D02*
G03X3937Y0I3937J0D01*
G01X0Y3937D02*
G03X3937Y0I3937J0D01*
G01D02*
X779528D01*
G01X3937D02*
X779528D01*
G01X0Y1456693D02*
Y3937D01*
G01Y1456693D02*
Y3937D01*
G01X7874Y1460630D02*
X3937D01*
G01D02*
X7874D01*
G01X3937D02*
G03X0Y1456693I0J-3937D01*
G01X3937Y1460630D02*
G03X0Y1456693I0J-3937D01*
G01X101378Y1519685D02*
G03X97441Y1515748I0J-3937D01*
G01X101378Y1519685D02*
G03X97441Y1515748I0J-3937D01*
G01D02*
Y1509055D01*
G01Y1515748D02*
Y1509055D01*
G01X93504Y1505118D02*
X67913D01*
G01X93504D02*
G03X97441Y1509055I0J3937D01*
G01X93504Y1505118D02*
G03X97441Y1509055I0J3937D01*
G01X67913Y1505118D02*
X93504D01*
G01X63976Y1515748D02*
G03X60039Y1519685I-3937J0D01*
G01X63976Y1515748D02*
G03X60039Y1519685I-3937J0D01*
G01X63976Y1509055D02*
Y1515748D01*
G01Y1509055D02*
G03X67913Y1505118I3937J0D01*
G01X63976Y1509055D02*
G03X67913Y1505118I3937J0D01*
G01X63976Y1515748D02*
Y1509055D01*
G01X7874Y1460630D02*
G03X11811Y1464567I0J3937D01*
G01X7874Y1460630D02*
G03X11811Y1464567I0J3937D01*
G01X15748Y1519685D02*
G03X11811Y1515748I0J-3937D01*
G01X15748Y1519685D02*
G03X11811Y1515748I0J-3937D01*
G01D02*
Y1464567D01*
G01Y1515748D02*
Y1464567D01*
G01X60039Y1519685D02*
X15748D01*
G01X60039D02*
X15748D01*
G01X141181Y277843D02*
G03X148106Y264712I37662J11471D01*
G01X141181Y277843D02*
G03X148106Y264712I37662J11471D01*
G01X141181Y277843D02*
G03X121220I-9980J-3040D01*
G01X114295Y264712D02*
G03X121220Y277843I-30737J24602D01*
G01X141181D02*
G03X121220I-9980J-3040D01*
G01X114295Y264712D02*
G03X121220Y277843I-30737J24601D01*
G01X114295Y264712D02*
G03X148106I16905J-13531D01*
G01X114295D02*
G03X148106I16905J-13531D01*
G01X141181Y730599D02*
G03X148106Y717468I37662J11471D01*
G01X141181Y730599D02*
G03X148106Y717468I37662J11471D01*
G01X141181Y730599D02*
G03X121220I-9980J-3040D01*
G01X114295Y717468D02*
G03X121220Y730599I-30737J24601D01*
G01X141181D02*
G03X121220I-9980J-3040D01*
G01X114295Y717468D02*
G03X121220Y730599I-30737J24601D01*
G01X114295Y717468D02*
G03X148106I16905J-13531D01*
G01X114295D02*
G03X148106I16905J-13531D01*
G01X114295Y1170224D02*
G03X148106I16905J-13531D01*
G01X114295D02*
G03X148106I16905J-13531D01*
G01X141181Y1183355D02*
G03X148106Y1170224I37662J11471D01*
G01X141181Y1183355D02*
G03X148106Y1170224I37662J11471D01*
G01X141181Y1183355D02*
G03X121220I-9980J-3040D01*
G01X141181D02*
G03X121220I-9980J-3040D01*
G01X114295Y1170224D02*
G03X121220Y1183355I-30737J24602D01*
G01X114295Y1170224D02*
G03X121220Y1183355I-30737J24601D01*
G01X280709Y1519685D02*
X101378D01*
G01X280709D02*
X101378D01*
G01X284646Y1515748D02*
G03X280709Y1519685I-3937J0D01*
G01X284646Y1515748D02*
G03X280709Y1519685I-3937J0D01*
G01X284646Y1500000D02*
Y1515748D01*
G01Y1500000D02*
G03X288583Y1496063I3937J0D01*
G01X493307D02*
X288583D01*
G01X284646Y1500000D02*
G03X288583Y1496063I3937J0D01*
G01X493307D02*
X288583D01*
G01X284646Y1515748D02*
Y1500000D01*
G01X389213Y277843D02*
G03X369252I-9981J-3040D01*
G01X389213D02*
G03X369252I-9981J-3040D01*
G01X362327Y264712D02*
G03X369252Y277843I-30737J24602D01*
G01X362327Y264712D02*
G03X369252Y277843I-30737J24602D01*
G01X362327Y264712D02*
G03X396138I16905J-13531D01*
G01X362327D02*
G03X396138I16905J-13531D01*
G01X389213Y730599D02*
G03X369252I-9981J-3040D01*
G01X389213D02*
G03X369252I-9981J-3040D01*
G01X362327Y717468D02*
G03X369252Y730599I-30737J24602D01*
G01X362327Y717468D02*
G03X369252Y730599I-30737J24602D01*
G01X362327Y717468D02*
G03X396138I16905J-13531D01*
G01X362327D02*
G03X396138I16905J-13531D01*
G01X362327Y1170224D02*
G03X396138I16905J-13531D01*
G01X362327D02*
G03X396138I16905J-13531D01*
G01X389213Y1183355D02*
G03X369252I-9981J-3040D01*
G01X389213D02*
G03X369252I-9981J-3040D01*
G01X362327Y1170224D02*
G03X369252Y1183355I-30737J24602D01*
G01X362327Y1170224D02*
G03X369252Y1183355I-30737J24602D01*
G01X322441Y1503937D02*
G03Y1496063I0J-3937D01*
G01X459449Y1503937D02*
X322441D01*
G01X459449D02*
X322441D01*
G01D02*
G03Y1496063I0J-3937D01*
G01X296457Y1519685D02*
G03X292520Y1515748I0J-3937D01*
G01X296457Y1519685D02*
X485433D01*
G01X296457D02*
G03X292520Y1515748I0J-3937D01*
G01X296457Y1519685D02*
X485433D01*
G01X304331Y1503937D02*
X292520D01*
G01Y1515748D02*
Y1503937D01*
G01X304331D02*
X292520D01*
G01Y1515748D02*
Y1503937D01*
G01X304331Y1496063D02*
G03Y1503937I0J3937D01*
G01Y1496063D02*
G03Y1503937I0J3937D01*
G01X389213Y277843D02*
G03X396138Y264712I37662J11471D01*
G01X389213Y277843D02*
G03X396138Y264712I37662J11470D01*
G01X389213Y730599D02*
G03X396138Y717468I37662J11471D01*
G01X389213Y730599D02*
G03X396138Y717468I37662J11470D01*
G01X389213Y1183355D02*
G03X396138Y1170224I37662J11471D01*
G01X389213Y1183355D02*
G03X396138Y1170224I37662J11470D01*
G01X477559Y1503937D02*
G03Y1496063I0J-3937D01*
G01X459449D02*
G03Y1503937I0J3937D01*
G01X489370D02*
X477559D01*
G01D02*
G03Y1496063I0J-3937D01*
G01X459449D02*
G03Y1503937I0J3937D01*
G01X489370D02*
X477559D01*
G01X489370Y1515748D02*
G03X485433Y1519685I-3937J0D01*
G01X489370Y1515748D02*
G03X485433Y1519685I-3937J0D01*
G01X501181D02*
G03X497244Y1515748I0J-3937D01*
G01X680512Y1519685D02*
X501181D01*
G01D02*
G03X497244Y1515748I0J-3937D01*
G01X680512Y1519685D02*
X501181D01*
G01X489370Y1515748D02*
Y1503937D01*
G01X493307Y1496063D02*
G03X497244Y1500000I0J3937D01*
G01Y1515748D02*
Y1500000D01*
G01X489370Y1515748D02*
Y1503937D01*
G01X493307Y1496063D02*
G03X497244Y1500000I0J3937D01*
G01Y1515748D02*
Y1500000D01*
G01X637244Y277843D02*
G03X644169Y264712I37662J11471D01*
G01X637244Y277843D02*
G03X644169Y264712I37662J11471D01*
G01X637244Y277843D02*
G03X617283I-9980J-3040D01*
G01X610358Y264712D02*
G03X617283Y277843I-30737J24602D01*
G01X637244D02*
G03X617283I-9980J-3040D01*
G01X610358Y264712D02*
G03X617283Y277843I-30737J24601D01*
G01X610358Y264712D02*
G03X644169I16906J-13531D01*
G01X610358D02*
G03X644169I16906J-13531D01*
G01X637244Y730599D02*
G03X644169Y717468I37662J11471D01*
G01X637244Y730599D02*
G03X644169Y717468I37662J11471D01*
G01X637244Y730599D02*
G03X617283I-9980J-3040D01*
G01X610358Y717468D02*
G03X617283Y730599I-30737J24601D01*
G01X637244D02*
G03X617283I-9980J-3040D01*
G01X610358Y717468D02*
G03X617283Y730599I-30737J24601D01*
G01X610358Y717468D02*
G03X644169I16906J-13531D01*
G01X610358D02*
G03X644169I16906J-13531D01*
G01X610358Y1170224D02*
G03X644169I16906J-13531D01*
G01X610358D02*
G03X644169I16906J-13531D01*
G01X637244Y1183355D02*
G03X644169Y1170224I37662J11471D01*
G01X637244Y1183355D02*
G03X644169Y1170224I37662J11471D01*
G01X637244Y1183355D02*
G03X617283I-9980J-3040D01*
G01X637244D02*
G03X617283I-9980J-3040D01*
G01X610358Y1170224D02*
G03X617283Y1183355I-30737J24602D01*
G01X610358Y1170224D02*
G03X617283Y1183355I-30737J24601D01*
G01X730339Y383610D02*
G03X764149I16905J-13531D01*
G01X730339Y383609D02*
G03X764150I16905J-13530D01*
G01X757225Y396741D02*
G03X764149Y383610I37663J11469D01*
G01X757224Y396741D02*
G03X764150Y383609I37662J11471D01*
G01X757225Y396741D02*
G03X737264I-9981J-3040D01*
G01X730339Y383610D02*
G03X737264Y396741I-30737J24602D01*
G01X757224D02*
G03X737264I-9980J-3041D01*
G01X730339Y383609D02*
G03X737264Y396741I-30738J24601D01*
G01X757225Y829811D02*
G03X764149Y816680I37663J11469D01*
G01X757224Y829811D02*
G03X764150Y816680I37662J11473D01*
G01X757225Y829811D02*
G03X737264I-9981J-3039D01*
G01X757224D02*
G03X737264I-9980J-3040D01*
G01X730339Y816680D02*
G03X737264Y829811I-30737J24602D01*
G01X730339Y816680D02*
G03X737264Y829811I-30737J24602D01*
G01X730339Y816680D02*
G03X764149I16905J-13531D01*
G01X730339D02*
G03X764150I16905J-13531D01*
G01X721850Y1519685D02*
G03X717913Y1515748I0J-3937D01*
G01X775591Y1519685D02*
X721850D01*
G01D02*
G03X717913Y1515748I0J-3937D01*
G01X775591Y1519685D02*
X721850D01*
G01X713976Y1505118D02*
G03X717913Y1509055I0J3937D01*
G01Y1515748D02*
Y1509055D01*
G01X713976Y1505118D02*
G03X717913Y1509055I0J3937D01*
G01Y1515748D02*
Y1509055D01*
G01X684449Y1515748D02*
G03X680512Y1519685I-3937J0D01*
G01X684449Y1515748D02*
G03X680512Y1519685I-3937J0D01*
G01X684449Y1509055D02*
Y1515748D01*
G01Y1509055D02*
G03X688386Y1505118I3937J0D01*
G01X713976D02*
X688386D01*
G01X684449Y1509055D02*
G03X688386Y1505118I3937J0D01*
G01D02*
X713976D01*
G01X684449Y1515748D02*
Y1509055D01*
G01X791339Y3937D02*
G03X795276Y0I3937J0D01*
G01D02*
X892317D01*
G01X791339Y3937D02*
Y23622D01*
G01Y3937D02*
G03X795276Y0I3937J0D01*
G01X791339Y3937D02*
Y23622D01*
G01X795276Y0D02*
X892317D01*
G01X783465Y54331D02*
G03X791339I3937J0D01*
G01X783465D02*
G03X791339I3937J0D01*
G01Y23622D02*
G03X783465I-3937J0D01*
G01X791339D02*
G03X783465I-3937J0D01*
G01X779528Y0D02*
G03X783465Y3937I0J3937D01*
G01X779528Y0D02*
G03X783465Y3937I0J3937D01*
G01X791339Y54331D02*
Y181890D01*
G01Y54331D02*
Y181890D01*
G01X783465Y3937D02*
Y185827D01*
G01Y3937D02*
Y185827D01*
G01X811024Y181890D02*
G03X822835Y193701I0J11811D01*
G01X791339Y181890D02*
X811024D01*
G01D02*
G03X822835Y193701I0J11811D01*
G01X791339Y181890D02*
X811024D01*
G01X787402Y189764D02*
G03X783465Y185827I0J-3937D01*
G01X787402Y189764D02*
G03X783465Y185827I0J-3937D01*
G01X811024Y189764D02*
G03X814961Y193701I0J3937D01*
G01X787402Y189764D02*
X811024D01*
G01D02*
G03X814961Y193701I0J3937D01*
G01X787402Y189764D02*
X811024D01*
G01X822835Y193701D02*
Y240157D01*
G01Y193701D02*
Y240157D01*
G01X814961Y193701D02*
Y244094D01*
G01Y193701D02*
Y244094D01*
G01X818898Y248031D02*
G03X814961Y244094I0J-3937D01*
G01X818898Y248031D02*
G03X814961Y244094I0J-3937D01*
G01X928098Y240157D02*
X822835D01*
G01X928098D02*
X822835D01*
G01X818898Y248031D02*
X1055118D01*
G01D02*
X818898D01*
G01X954331Y1503937D02*
X817323D01*
G01X954331D02*
X817323D01*
G01X791339Y1519685D02*
G03X787402Y1515748I0J-3937D01*
G01X791339Y1519685D02*
X980315D01*
G01X791339D02*
G03X787402Y1515748I0J-3937D01*
G01X791339Y1519685D02*
X980315D01*
G01X817323Y1503937D02*
G03Y1496063I0J-3937D01*
G01X799213D02*
G03Y1503937I0J3937D01*
G01D02*
X787402D01*
G01Y1515748D02*
Y1503937D01*
G01X799213D02*
X787402D01*
G01X817323D02*
G03Y1496063I0J-3937D01*
G01X799213D02*
G03Y1503937I0J3937D01*
G01X787402Y1515748D02*
Y1503937D01*
G01X779528Y1515748D02*
G03X775591Y1519685I-3937J0D01*
G01X779528Y1515748D02*
G03X775591Y1519685I-3937J0D01*
G01X779528Y1500000D02*
Y1515748D01*
G01Y1500000D02*
G03X783465Y1496063I3937J0D01*
G01X988189D02*
X783465D01*
G01X779528Y1500000D02*
G03X783465Y1496063I3937J0D01*
G01X988189D02*
X783465D01*
G01X779528Y1515748D02*
Y1500000D01*
G01X900191Y0D02*
G03X892317I-3937J0D01*
G01X896254D02*
Y-394D01*
G01Y0D02*
Y394D01*
G01X895762Y0D02*
X896746D01*
G01X900191D02*
G03X892317I-3937J0D01*
G01X900191D02*
X1212598D01*
G01X900191D02*
X1212598D01*
G01X953294Y248031D02*
G03Y240157I1J-3937D01*
G01X1051181D02*
X953294D01*
G01Y248031D02*
G03Y240157I1J-3937D01*
G01X928098D02*
G03Y248031I0J3937D01*
G01Y240157D02*
G03Y248031I0J3937D01*
G01X1051181Y240157D02*
X953294D01*
G01X971398Y718788D02*
G03X951437I-9980J-3040D01*
G01X944512Y705657D02*
G03X951437Y718788I-30737J24602D01*
G01X971398D02*
G03X951437I-9980J-3040D01*
G01X944512Y705657D02*
G03X951437Y718788I-30737J24602D01*
G01X944512Y705657D02*
G03X978323I16905J-13531D01*
G01X944512D02*
G03X978323I16905J-13531D01*
G01X944512Y974161D02*
G03X978323I16905J-13531D01*
G01X944512D02*
G03X978323I16905J-13531D01*
G01X971398Y987292D02*
G03X951437I-9980J-3040D01*
G01X944512Y974161D02*
G03X951437Y987292I-30737J24602D01*
G01X971398D02*
G03X951437I-9980J-3040D01*
G01X944512Y974161D02*
G03X951437Y987292I-30737J24602D01*
G01X954331Y1496063D02*
G03Y1503937I0J3937D01*
G01Y1496063D02*
G03Y1503937I0J3937D01*
G01X1051181Y193701D02*
G03X1062992Y181890I11811J0D01*
G01X1051181Y193701D02*
G03X1062992Y181890I11811J0D01*
G01X1051181Y240157D02*
Y193701D01*
G01Y240157D02*
Y193701D01*
G01X971398Y718788D02*
G03X978323Y705657I37662J11471D01*
G01X971398Y718788D02*
G03X978323Y705657I37662J11470D01*
G01X971398Y987292D02*
G03X978323Y974161I37662J11471D01*
G01X971398Y987292D02*
G03X978323Y974161I37662J11470D01*
G01X1059196Y1519685D02*
X996063D01*
G01X1059196D02*
X996063D01*
G01X984252Y1515748D02*
G03X980315Y1519685I-3937J0D01*
G01X984252Y1515748D02*
G03X980315Y1519685I-3937J0D01*
G01X996063D02*
G03X992126Y1515748I0J-3937D01*
G01X996063Y1519685D02*
G03X992126Y1515748I0J-3937D01*
G01X972441Y1503937D02*
G03Y1496063I0J-3937D01*
G01X984252Y1503937D02*
X972441D01*
G01X984252Y1515748D02*
Y1503937D01*
G01X972441D02*
G03Y1496063I0J-3937D01*
G01X988189D02*
G03X992126Y1500000I0J3937D01*
G01Y1515748D02*
Y1500000D01*
G01X984252Y1515748D02*
Y1503937D01*
G01D02*
X972441D01*
G01X988189Y1496063D02*
G03X992126Y1500000I0J3937D01*
G01Y1515748D02*
Y1500000D01*
G01X1133071Y189764D02*
G03Y181890I0J-3937D01*
G01D02*
X1216535D01*
G01X1133071D02*
X1216535D01*
G01X1133071Y189764D02*
G03Y181890I0J-3937D01*
G01X1102362D02*
G03Y189764I0J3937D01*
G01Y181890D02*
G03Y189764I0J3937D01*
G01X1062992Y181890D02*
X1102362D01*
G01X1062992D02*
X1102362D01*
G01X1059055Y244094D02*
G03X1055118Y248031I-3937J0D01*
G01X1059055Y244094D02*
G03X1055118Y248031I-3937J0D01*
G01X1059055Y244094D02*
Y193701D01*
G01Y244094D02*
Y193701D01*
G01X1062992Y189764D02*
X1220472D01*
G01X1059055Y193701D02*
G03X1062992Y189764I3937J0D01*
G01X1059055Y193701D02*
G03X1062992Y189764I3937J0D01*
G01D02*
X1220472D01*
G01X1085630Y1417323D02*
G03X1089567Y1421260I0J3937D01*
G01X1085630Y1417323D02*
G03X1089567Y1421260I0J3937D01*
G01X1072638D02*
G03X1076575Y1417322I3937J-1D01*
G01X1085630Y1417323D02*
X1076575D01*
G01X1072638Y1421260D02*
G03X1076575Y1417323I3937J0D01*
G01D02*
X1085630D01*
G01X1089567Y1506243D02*
Y1421260D01*
G01Y1506243D02*
Y1421260D01*
G01X1072638D02*
Y1506243D01*
G01D02*
Y1421260D01*
G01X1103009Y1519685D02*
G03X1100225Y1518532I0J-3937D01*
G01X1207283Y1519685D02*
X1103009D01*
G01D02*
G03X1100225Y1518532I0J-3937D01*
G01X1207283Y1519685D02*
X1103009D01*
G01X1090720Y1509027D02*
G03X1089567Y1506243I2784J-2784D01*
G01X1100225Y1518532D02*
X1090720Y1509027D01*
G01D02*
G03X1089567Y1506243I2784J-2784D01*
G01X1100225Y1518532D02*
X1090720Y1509027D01*
G01X1061980Y1518532D02*
G03X1059196Y1519685I-2784J-2784D01*
G01X1061980Y1518532D02*
G03X1059196Y1519685I-2784J-2784D01*
G01X1071485Y1509027D02*
X1061980Y1518532D01*
G01X1072638Y1506243D02*
G03X1071485Y1509027I-3937J0D01*
G01X1072638Y1506243D02*
G03X1071485Y1509027I-3937J0D01*
G01X1061980Y1518532D02*
X1071485Y1509027D01*
G01X1216535Y54331D02*
G03X1224409I3937J0D01*
G01X1216535D02*
Y181890D01*
G01Y54331D02*
Y181890D01*
G01Y54331D02*
G03X1224409I3937J0D01*
G01Y23622D02*
G03X1216535I-3937J0D01*
G01X1224409D02*
G03X1216535I-3937J0D01*
G01X1212598Y0D02*
G03X1216535Y3937I0J3937D01*
G01D02*
Y23622D01*
G01X1212598Y0D02*
G03X1216535Y3937I0J3937D01*
G01X1224409D02*
G03X1228346Y0I3937J0D01*
G01X1224409Y185827D02*
Y3937D01*
G01X1216535D02*
Y23622D01*
G01X1224409Y3937D02*
G03X1228346Y0I3937J0D01*
G01X1224409Y3937D02*
Y185827D01*
G01X1228346Y0D02*
X1930906D01*
G01X1228346D02*
X1930906D01*
G01X1224409Y185827D02*
G03X1220472Y189764I-3937J0D01*
G01X1224409Y185827D02*
G03X1220472Y189764I-3937J0D01*
G01X1164984Y383609D02*
G03X1198795I16906J-13530D01*
G01X1164984D02*
G03X1198795I16906J-13530D01*
G01X1191870Y396741D02*
G03X1198795Y383610I37662J11471D01*
G01X1191870Y396741D02*
G03X1198795Y383609I37663J11469D01*
G01X1191870Y396741D02*
G03X1171909I-9980J-3040D01*
G01X1164984Y383610D02*
G03X1171909Y396741I-30737J24602D01*
G01X1191870D02*
G03X1171909I-9980J-3040D01*
G01X1164984Y383609D02*
G03X1171909Y396741I-30737J24601D01*
G01X1164984Y974161D02*
G03X1198795I16906J-13531D01*
G01X1164984D02*
G03X1198795I16906J-13531D01*
G01X1191870Y987292D02*
G03X1198795Y974161I37662J11471D01*
G01X1191870Y987292D02*
G03X1198795Y974161I37662J11471D01*
G01X1191870Y987292D02*
G03X1171909I-9980J-3040D01*
G01X1164984Y974161D02*
G03X1171909Y987292I-30737J24602D01*
G01X1191870D02*
G03X1171909I-9980J-3040D01*
G01X1164984Y974161D02*
G03X1171909Y987292I-30737J24601D01*
G01X1240748Y1505118D02*
G03X1244685Y1509055I0J3937D01*
G01X1240748Y1505118D02*
G03X1244685Y1509055I0J3937D01*
G01X1211220Y1515748D02*
G03X1207283Y1519685I-3937J0D01*
G01X1211220Y1515748D02*
G03X1207283Y1519685I-3937J0D01*
G01X1211220Y1509055D02*
Y1515748D01*
G01Y1509055D02*
G03X1215157Y1505118I3937J0D01*
G01X1240748D02*
X1215157D01*
G01X1211220Y1509055D02*
G03X1215157Y1505118I3937J0D01*
G01D02*
X1240748D01*
G01X1211220Y1515748D02*
Y1509055D01*
G01X1311851Y277843D02*
G03X1318775Y264712I37663J11469D01*
G01X1311850Y277843D02*
G03X1318776Y264712I37661J11473D01*
G01X1311851Y277843D02*
G03X1291890I-9980J-3040D01*
G01X1284965Y264712D02*
G03X1291890Y277843I-30737J24602D01*
G01X1311850D02*
G03X1291890I-9980J-3040D01*
G01X1284965Y264712D02*
G03X1291890Y277843I-30737J24602D01*
G01X1284965Y264712D02*
G03X1318775I16905J-13531D01*
G01X1284965D02*
G03X1318776I16906J-13531D01*
G01X1311851Y730599D02*
G03X1318775Y717468I37663J11469D01*
G01X1311850Y730599D02*
G03X1318776Y717468I37661J11473D01*
G01X1311851Y730599D02*
G03X1291890I-9980J-3040D01*
G01X1284965Y717468D02*
G03X1291891Y730599I-30736J24604D01*
G01X1311850D02*
G03X1291890I-9980J-3040D01*
G01X1284965Y717468D02*
G03X1291890Y730599I-30737J24602D01*
G01X1284965Y717468D02*
G03X1318775I16905J-13531D01*
G01X1284965D02*
G03X1318776I16906J-13531D01*
G01X1284965Y1170224D02*
G03X1318775I16905J-13531D01*
G01X1284965D02*
G03X1318776I16906J-13531D01*
G01X1311851Y1183355D02*
G03X1318775Y1170224I37663J11469D01*
G01X1311850Y1183355D02*
G03X1318776Y1170224I37661J11473D01*
G01X1311851Y1183355D02*
G03X1291890I-9980J-3040D01*
G01X1311850D02*
G03X1291890I-9980J-3040D01*
G01X1284965Y1170224D02*
G03X1291890Y1183355I-30737J24602D01*
G01X1284965Y1170224D02*
G03X1291890Y1183355I-30737J24602D01*
G01X1248622Y1519685D02*
G03X1244685Y1515748I0J-3937D01*
G01X1427953Y1519685D02*
X1248622D01*
G01D02*
G03X1244685Y1515748I0J-3937D01*
G01X1427953Y1519685D02*
X1248622D01*
G01X1244685Y1515748D02*
Y1509055D01*
G01Y1515748D02*
Y1509055D01*
G01X1431890Y1515748D02*
G03X1427953Y1519685I-3937J0D01*
G01X1431890Y1515748D02*
G03X1427953Y1519685I-3937J0D01*
G01X1431890Y1500000D02*
Y1515748D01*
G01Y1500000D02*
G03X1435827Y1496063I3937J0D01*
G01X1431890Y1500000D02*
G03X1435827Y1496063I3937J0D01*
G01X1431890Y1515748D02*
Y1500000D01*
G01X1532996Y264712D02*
G03X1566807I16906J-13531D01*
G01X1532996D02*
G03X1566807I16906J-13531D01*
G01X1532996Y717468D02*
G03X1566807I16906J-13531D01*
G01X1532996D02*
G03X1566807I16906J-13531D01*
G01X1532996Y1170224D02*
G03X1566807I16906J-13531D01*
G01X1532996D02*
G03X1566807I16906J-13531D01*
G01X1469685Y1503937D02*
G03Y1496063I0J-3937D01*
G01X1451575D02*
G03Y1503937I0J3937D01*
G01X1606693D02*
X1469685D01*
G01X1606693D02*
X1469685D01*
G01D02*
G03Y1496063I0J-3937D01*
G01X1451575D02*
G03Y1503937I0J3937D01*
G01X1443701Y1519685D02*
G03X1439764Y1515748I0J-3937D01*
G01X1443701Y1519685D02*
X1632677D01*
G01X1443701D02*
G03X1439764Y1515748I0J-3937D01*
G01X1443701Y1519685D02*
X1632677D01*
G01X1451575Y1503937D02*
X1439764D01*
G01Y1515748D02*
Y1503937D01*
G01X1451575D02*
X1439764D01*
G01X1640551Y1496063D02*
X1435827D01*
G01X1439764Y1515748D02*
Y1503937D01*
G01X1640551Y1496063D02*
X1435827D01*
G01X1559882Y277843D02*
G03X1566807Y264712I37662J11471D01*
G01X1559882Y277843D02*
G03X1539921I-9980J-3040D01*
G01X1559882D02*
G03X1566807Y264712I37662J11471D01*
G01X1559882Y277843D02*
G03X1539921I-9980J-3040D01*
G01X1532996Y264712D02*
G03X1539921Y277843I-30737J24602D01*
G01X1532996Y264712D02*
G03X1539921Y277843I-30737J24602D01*
G01X1559882Y730599D02*
G03X1566807Y717468I37662J11471D01*
G01X1559882Y730599D02*
G03X1539921I-9980J-3040D01*
G01X1559882D02*
G03X1566807Y717468I37662J11471D01*
G01X1559882Y730599D02*
G03X1539921I-9980J-3040D01*
G01X1532996Y717468D02*
G03X1539921Y730599I-30737J24601D01*
G01X1532996Y717468D02*
G03X1539921Y730599I-30737J24601D01*
G01X1559882Y1183355D02*
G03X1539921I-9980J-3040D01*
G01X1559882D02*
G03X1539921I-9980J-3040D01*
G01X1559882D02*
G03X1566807Y1170224I37662J11471D01*
G01X1559882Y1183355D02*
G03X1566807Y1170224I37662J11471D01*
G01X1532996D02*
G03X1539921Y1183355I-30737J24602D01*
G01X1532996Y1170224D02*
G03X1539921Y1183355I-30737J24601D01*
G01X1636614Y1503937D02*
X1624803D01*
G01X1636614D02*
X1624803D01*
G01D02*
G03Y1496063I0J-3937D01*
G01X1606693D02*
G03Y1503937I0J3937D01*
G01X1624803D02*
G03Y1496063I0J-3937D01*
G01X1606693D02*
G03Y1503937I0J3937D01*
G01X1636614Y1515748D02*
G03X1632677Y1519685I-3937J0D01*
G01X1636614Y1515748D02*
G03X1632677Y1519685I-3937J0D01*
G01X1648425D02*
G03X1644488Y1515748I0J-3937D01*
G01X1827756Y1519685D02*
X1648425D01*
G01D02*
G03X1644488Y1515748I0J-3937D01*
G01X1827756Y1519685D02*
X1648425D01*
G01X1636614Y1515748D02*
Y1503937D01*
G01X1640551Y1496063D02*
G03X1644488Y1500000I0J3937D01*
G01Y1515748D02*
Y1500000D01*
G01X1636614Y1515748D02*
Y1503937D01*
G01X1640551Y1496063D02*
G03X1644488Y1500000I0J3937D01*
G01Y1515748D02*
Y1500000D01*
G01X1807914Y277843D02*
G03X1814838Y264712I37663J11469D01*
G01X1807913Y277843D02*
G03X1814839Y264712I37661J11473D01*
G01X1807914Y277843D02*
G03X1787953I-9980J-3040D01*
G01X1781028Y264712D02*
G03X1787953Y277843I-30737J24602D01*
G01X1807913D02*
G03X1787953I-9980J-3040D01*
G01X1781028Y264712D02*
G03X1787953Y277843I-30737J24602D01*
G01X1781028Y264712D02*
G03X1814839I16906J-13531D01*
G01X1781028D02*
G03X1814839I16906J-13531D01*
G01X1807914Y730599D02*
G03X1814838Y717468I37663J11469D01*
G01X1807913Y730599D02*
G03X1814839Y717468I37661J11473D01*
G01X1807914Y730599D02*
G03X1787953I-9980J-3040D01*
G01X1781028Y717468D02*
G03X1787954Y730599I-30736J24604D01*
G01X1807913D02*
G03X1787953I-9980J-3040D01*
G01X1781028Y717468D02*
G03X1787953Y730599I-30737J24602D01*
G01X1781028Y717468D02*
G03X1814838I16905J-13531D01*
G01X1781028D02*
G03X1814839I16906J-13531D01*
G01X1781028Y1170224D02*
G03X1814838I16905J-13531D01*
G01X1781028D02*
G03X1814839I16906J-13531D01*
G01X1807914Y1183355D02*
G03X1814838Y1170224I37662J11468D01*
G01X1807913Y1183355D02*
G03X1814839Y1170224I37661J11473D01*
G01X1807914Y1183355D02*
G03X1787953I-9980J-3040D01*
G01X1807913D02*
G03X1787953I-9980J-3040D01*
G01X1781028Y1170224D02*
G03X1787953Y1183355I-30737J24602D01*
G01X1781028Y1170224D02*
G03X1787953Y1183355I-30737J24602D01*
G01X1869094Y1519685D02*
G03X1865157Y1515748I0J-3937D01*
G01X1919094Y1519685D02*
X1869094D01*
G01D02*
G03X1865157Y1515748I0J-3937D01*
G01X1919094Y1519685D02*
X1869094D01*
G01X1865157Y1515748D02*
Y1509055D01*
G01Y1515748D02*
Y1509055D01*
G01X1861220Y1505118D02*
X1835630D01*
G01X1861220D02*
G03X1865157Y1509055I0J3937D01*
G01X1861220Y1505118D02*
G03X1865157Y1509055I0J3937D01*
G01X1835630Y1505118D02*
X1861220D01*
G01X1831693Y1515748D02*
G03X1827756Y1519685I-3937J0D01*
G01X1831693Y1515748D02*
G03X1827756Y1519685I-3937J0D01*
G01X1831693Y1509055D02*
Y1515748D01*
G01Y1509055D02*
G03X1835630Y1505118I3937J0D01*
G01X1831693Y1509055D02*
G03X1835630Y1505118I3937J0D01*
G01X1831693Y1515748D02*
Y1509055D01*
G01X1930906Y0D02*
G03X1934843Y3937I0J3937D01*
G01X1930906Y0D02*
G03X1934843Y3937I0J3937D01*
G01D02*
Y1456693D01*
G01Y3937D02*
Y1456693D01*
G01X1930906Y1460630D02*
X1926969D01*
G01X1934843Y1456693D02*
G03X1930906Y1460630I-3937J0D01*
G01X1934843Y1456693D02*
G03X1930906Y1460630I-3937J0D01*
G01D02*
X1926969D01*
G01X1923031Y1515748D02*
G03X1919094Y1519685I-3937J0D01*
G01X1923031Y1515748D02*
G03X1919094Y1519685I-3937J0D01*
G01X1923031Y1464567D02*
Y1515748D01*
G01Y1464567D02*
G03X1926969Y1460630I3937J0D01*
G01X1923031Y1464567D02*
G03X1926969Y1460630I3937J0D01*
G01X1923031Y1515748D02*
Y1464567D01*
G54D48*
X1021216Y1137521D03*
G54D39*
X516898Y1438421D03*
X1026700Y1133600D03*
X1013231Y1098071D03*
X986500Y1122200D03*
G54D49*
X1021216Y1143121D03*
M02*
